FILE_TYPE = MACRO_DRAWING;
SET COLOR_WIRE YELLOW;
SET COLOR_PROP ORANGE;
SET COLOR_DOT WHITE;
SET COLOR_ARC YELLOW;
SET COLOR_BODY GREEN;
SET COLOR_NOTE PURPLE;
SET PROP_DISPLAY VALUE;
SET PAGE_NUMBER P132;
FORCEADD OFFPAGE..1
(-5225 -1350);
FORCEPROP 2 LAST $XR1 164 
J 0
(-5597 -1350);
DISPLAY 0.638298 (-5597 -1350);
PAINT MONO (-5597 -1350);
FORCEPROP 2 LAST $XR0 162 
J 0
(-5477 -1350);
DISPLAY 0.638298 (-5477 -1350);
PAINT MONO (-5477 -1350);
FORCEPROP 2 LAST CDS_LIB standard
J 0
(-5225 -1350);
PAINT MONO (-5225 -1350);
DISPLAY INVISIBLE (-5225 -1350);
FORCEPROP 1 LAST COMMENT_BODY TRUE
J 0
(-5100 -1450);
DISPLAY 0.872340 (-5100 -1450);
PAINT GREEN (-5100 -1450);
DISPLAY INVISIBLE (-5100 -1450);
FORCEPROP 1 LAST OFFPAGE TRUE
J 0
(-4900 -1475);
DISPLAY 0.872340 (-4900 -1475);
PAINT GREEN (-4900 -1475);
DISPLAY INVISIBLE (-4900 -1475);
FORCEPROP 2 LAST PATH I1
J 0
(-5475 -1300);
DISPLAY 1.021277 (-5475 -1300);
DISPLAY INVISIBLE (-5475 -1300);
FORCEADD Q_RES..1
(-2200 1100);
FORCEPROP 1 LAST PART_NUMBER CS03322FB03
J 0
(-2325 1150);
DISPLAY 0.638298 (-2325 1150);
DISPLAY INVISIBLE (-2325 1150);
FORCEPROP 1 LAST MATERIAL CHIP
J 0
(-2125 1100);
DISPLAY 0.638298 (-2125 1100);
FORCEPROP 1 LAST VALUE 33.2
J 2
(-2025 1075);
DISPLAY 0.510638 (-2025 1075);
FORCEPROP 1 LAST PACK_TYPE 0402LF
J 0
(-1900 1075);
DISPLAY 0.510638 (-1900 1075);
FORCEPROP 1 LAST TOLERANCE 1%
J 0
(-2000 1075);
DISPLAY 0.510638 (-2000 1075);
FORCEPROP 1 LAST LOCATION R4616
J 0
(-2425 1100);
DISPLAY 0.638298 (-2425 1100);
FORCEPROP 1 LASTPIN (-2300 1100) $PN 1
J 0
(-2288 1112);
DISPLAY 0.787234 (-2288 1112);
PAINT MONO (-2288 1112);
FORCEPROP 1 LASTPIN (-2100 1100) $PN 2
J 0
(-2138 1112);
DISPLAY 0.787234 (-2138 1112);
PAINT MONO (-2138 1112);
FORCEPROP 2 LAST CDS_LIB pure_quanta
J 0
(-2200 1100);
DISPLAY INVISIBLE (-2200 1100);
FORCEPROP 1 LAST PATH I100
J 0
(-2250 1250);
DISPLAY 0.978723 (-2250 1250);
PAINT WHITE (-2250 1250);
DISPLAY INVISIBLE (-2250 1250);
FORCEPROP 1 LAST WATTAGE 1/16W
J 2
(-2000 1200);
DISPLAY 0.638298 (-2000 1200);
DISPLAY INVISIBLE (-2000 1200);
FORCEPROP 0 LAST $SEC 1
J 0
(-2125 1150);
DISPLAY 0.680851 (-2125 1150);
PAINT MONO (-2125 1150);
DISPLAY INVISIBLE (-2125 1150);
FORCEPROP 0 LAST CDS_SEC 1
J 0
(-2125 1150);
DISPLAY 1.021277 (-2125 1150);
DISPLAY INVISIBLE (-2125 1150);
FORCEADD OFFPAGE..1
(-1525 -450);
FORCEPROP 2 LAST $XR0 213 
J 0
(-1777 -450);
DISPLAY 0.638298 (-1777 -450);
PAINT MONO (-1777 -450);
FORCEPROP 2 LAST CDS_LIB standard
J 0
(-1525 -450);
DISPLAY INVISIBLE (-1525 -450);
FORCEPROP 1 LAST OFFPAGE TRUE
J 0
(-1200 -575);
DISPLAY 0.872340 (-1200 -575);
PAINT GREEN (-1200 -575);
DISPLAY INVISIBLE (-1200 -575);
FORCEPROP 1 LAST COMMENT_BODY TRUE
J 0
(-1400 -550);
DISPLAY 0.872340 (-1400 -550);
PAINT GREEN (-1400 -550);
DISPLAY INVISIBLE (-1400 -550);
FORCEPROP 2 LAST PATH I101
J 0
(-1800 -400);
DISPLAY 1.021277 (-1800 -400);
DISPLAY INVISIBLE (-1800 -400);
FORCEADD OFFPAGE..1
(-1525 -350);
FORCEPROP 2 LAST $XR1 216 
J 0
(-1897 -350);
DISPLAY 0.638298 (-1897 -350);
PAINT MONO (-1897 -350);
FORCEPROP 2 LAST $XR0 164 
J 0
(-1777 -350);
DISPLAY 0.638298 (-1777 -350);
PAINT MONO (-1777 -350);
FORCEPROP 2 LAST PATH I102
J 0
(-1800 -300);
DISPLAY 1.021277 (-1800 -300);
DISPLAY INVISIBLE (-1800 -300);
FORCEPROP 2 LAST CDS_LIB standard
J 0
(-1525 -350);
DISPLAY INVISIBLE (-1525 -350);
FORCEPROP 1 LAST OFFPAGE TRUE
J 0
(-1200 -475);
DISPLAY 0.872340 (-1200 -475);
PAINT GREEN (-1200 -475);
DISPLAY INVISIBLE (-1200 -475);
FORCEPROP 1 LAST COMMENT_BODY TRUE
J 0
(-1400 -450);
DISPLAY 0.872340 (-1400 -450);
PAINT GREEN (-1400 -450);
DISPLAY INVISIBLE (-1400 -450);
FORCEADD Q_RES..1
(-550 -450);
FORCEPROP 1 LAST PART_NUMBER CS03322FB03
J 0
(-675 -400);
DISPLAY 0.638298 (-675 -400);
DISPLAY INVISIBLE (-675 -400);
FORCEPROP 1 LAST MATERIAL CHIP
J 0
(-775 -500);
DISPLAY 0.638298 (-775 -500);
FORCEPROP 1 LAST VALUE 33.2
J 2
(-375 -475);
DISPLAY 0.510638 (-375 -475);
FORCEPROP 1 LAST TOLERANCE 1%
J 0
(-350 -475);
DISPLAY 0.510638 (-350 -475);
FORCEPROP 1 LAST PACK_TYPE 0402LF
J 0
(-250 -475);
DISPLAY 0.510638 (-250 -475);
FORCEPROP 1 LAST $LOCATION R4755
J 0
(-775 -450);
DISPLAY 0.638298 (-775 -450);
FORCEPROP 1 LASTPIN (-650 -450) $PN 1
J 0
(-638 -438);
DISPLAY 0.787234 (-638 -438);
PAINT MONO (-638 -438);
FORCEPROP 1 LASTPIN (-450 -450) $PN 2
J 0
(-488 -438);
DISPLAY 0.787234 (-488 -438);
PAINT MONO (-488 -438);
FORCEPROP 1 LAST PATH I103
J 0
(-600 -300);
DISPLAY 0.978723 (-600 -300);
PAINT WHITE (-600 -300);
DISPLAY INVISIBLE (-600 -300);
FORCEPROP 2 LAST CDS_LIB pure_quanta
J 0
(-550 -450);
DISPLAY INVISIBLE (-550 -450);
FORCEPROP 1 LAST WATTAGE 1/16W
J 2
(-350 -350);
DISPLAY 0.638298 (-350 -350);
DISPLAY INVISIBLE (-350 -350);
FORCEPROP 0 LAST CDS_LOCATION R4755
J 0
(-700 -400);
DISPLAY 1.021277 (-700 -400);
DISPLAY INVISIBLE (-700 -400);
FORCEPROP 0 LAST $SEC 1
J 0
(-700 -400);
DISPLAY 0.680851 (-700 -400);
PAINT MONO (-700 -400);
DISPLAY INVISIBLE (-700 -400);
FORCEPROP 0 LAST CDS_SEC 1
J 0
(-700 -400);
DISPLAY 1.021277 (-700 -400);
DISPLAY INVISIBLE (-700 -400);
FORCEADD Q_RES..1
(-550 -350);
FORCEPROP 1 LAST PART_NUMBER CS03322FB03
J 0
(-675 -300);
DISPLAY 0.638298 (-675 -300);
DISPLAY INVISIBLE (-675 -300);
FORCEPROP 1 LAST VALUE 33.2
J 2
(-375 -375);
DISPLAY 0.510638 (-375 -375);
FORCEPROP 1 LAST MATERIAL CHIP
J 0
(-775 -400);
DISPLAY 0.638298 (-775 -400);
FORCEPROP 1 LAST PACK_TYPE 0402LF
J 0
(-250 -375);
DISPLAY 0.510638 (-250 -375);
FORCEPROP 1 LAST TOLERANCE 1%
J 0
(-350 -375);
DISPLAY 0.510638 (-350 -375);
FORCEPROP 1 LAST $LOCATION R4754
J 0
(-775 -350);
DISPLAY 0.638298 (-775 -350);
FORCEPROP 1 LASTPIN (-650 -350) $PN 1
J 0
(-638 -338);
DISPLAY 0.787234 (-638 -338);
PAINT MONO (-638 -338);
FORCEPROP 1 LASTPIN (-450 -350) $PN 2
J 0
(-488 -338);
DISPLAY 0.787234 (-488 -338);
PAINT MONO (-488 -338);
FORCEPROP 1 LAST PATH I104
J 0
(-600 -200);
DISPLAY 0.978723 (-600 -200);
PAINT WHITE (-600 -200);
DISPLAY INVISIBLE (-600 -200);
FORCEPROP 1 LAST WATTAGE 1/16W
J 2
(-350 -250);
DISPLAY 0.638298 (-350 -250);
DISPLAY INVISIBLE (-350 -250);
FORCEPROP 2 LAST CDS_LIB pure_quanta
J 0
(-550 -350);
DISPLAY INVISIBLE (-550 -350);
FORCEPROP 0 LAST CDS_LOCATION R4754
J 0
(-700 -300);
DISPLAY 1.021277 (-700 -300);
DISPLAY INVISIBLE (-700 -300);
FORCEPROP 0 LAST $SEC 1
J 0
(-700 -300);
DISPLAY 0.680851 (-700 -300);
PAINT MONO (-700 -300);
DISPLAY INVISIBLE (-700 -300);
FORCEPROP 0 LAST CDS_SEC 1
J 0
(-700 -300);
DISPLAY 1.021277 (-700 -300);
DISPLAY INVISIBLE (-700 -300);
FORCEADD Q_RES..2
(-275 0);
FORCEPROP 1 LAST PART_NUMBER CS31002FB08
J 0
(-235 -125);
DISPLAY 0.787234 (-235 -125);
DISPLAY INVISIBLE (-235 -125);
FORCEPROP 1 LAST VALUE 10K
J 0
(-230 75);
DISPLAY 0.787234 (-230 75);
FORCEPROP 1 LAST MATERIAL CHIP
J 0
(-235 -75);
DISPLAY 0.787234 (-235 -75);
FORCEPROP 1 LAST WATTAGE 1/16W
J 0
(-235 -25);
DISPLAY 0.787234 (-235 -25);
FORCEPROP 1 LAST PACK_TYPE 0402LF
J 0
(-235 -175);
DISPLAY 0.787234 (-235 -175);
FORCEPROP 1 LAST TOLERANCE 1%
J 0
(-230 25);
DISPLAY 0.787234 (-230 25);
FORCEPROP 1 LAST $LOCATION R4756
J 0
(-230 125);
DISPLAY 0.787234 (-230 125);
FORCEPROP 1 LASTPIN (-275 100) $PN 1
J 0
(-270 62);
DISPLAY 0.787234 (-270 62);
PAINT MONO (-270 62);
FORCEPROP 1 LASTPIN (-275 -100) $PN 2
J 0
(-270 -90);
DISPLAY 0.787234 (-270 -90);
PAINT MONO (-270 -90);
FORCEPROP 1 LAST PATH I105
J 0
(-225 175);
DISPLAY 0.978723 (-225 175);
PAINT WHITE (-225 175);
DISPLAY INVISIBLE (-225 175);
FORCEPROP 2 LAST CDS_LIB pure_quanta
J 0
(-275 0);
DISPLAY INVISIBLE (-275 0);
FORCEPROP 0 LAST CDS_LOCATION R4756
J 0
(-225 175);
DISPLAY 1.021277 (-225 175);
DISPLAY INVISIBLE (-225 175);
FORCEPROP 0 LAST $SEC 1
J 0
(-225 175);
DISPLAY 0.680851 (-225 175);
PAINT MONO (-225 175);
DISPLAY INVISIBLE (-225 175);
FORCEPROP 0 LAST CDS_SEC 1
J 0
(-225 175);
DISPLAY 1.021277 (-225 175);
DISPLAY INVISIBLE (-225 175);
FORCEADD UNIVERSAL_POWER..1
(-275 200);
FORCEPROP 3 LASTPIN (-275 150) SIG_NAME P3V3_AUX\g
J 0
(-265 160);
DISPLAY 0.659574 (-265 160);
PAINT MONO (-265 160);
DISPLAY INVISIBLE (-265 160);
FORCEPROP 1 LAST HDL_POWER P3V3_AUX
J 1
(-275 250);
DISPLAY 0.872340 (-275 250);
PAINT GREEN (-275 250);
FORCEPROP 1 LAST PATH I106
J 0
(-225 225);
DISPLAY 0.872340 (-225 225);
PAINT AQUA (-225 225);
DISPLAY INVISIBLE (-225 225);
FORCEPROP 2 LAST CDS_LIB logical_power
J 0
(-275 200);
DISPLAY INVISIBLE (-275 200);
FORCEADD Q_RES..1
(1175 -825);
FORCEPROP 1 LAST PART_NUMBER CS00002JB13
J 0
(1050 -750);
DISPLAY 0.638298 (1050 -750);
DISPLAY INVISIBLE (1050 -750);
FORCEPROP 1 LAST MATERIAL EMPTY
J 0
(1325 -875);
DISPLAY 0.638298 (1325 -875);
PAINT RED (1325 -875);
FORCEPROP 1 LAST TOLERANCE 5%
J 0
(1375 -825);
DISPLAY 0.638298 (1375 -825);
FORCEPROP 1 LAST PACK_TYPE 0402LF
J 0
(1450 -825);
DISPLAY 0.638298 (1450 -825);
FORCEPROP 1 LAST VALUE 0
J 2
(1350 -825);
DISPLAY 0.638298 (1350 -825);
FORCEPROP 1 LAST $LOCATION R4758
J 0
(950 -825);
DISPLAY 0.638298 (950 -825);
FORCEPROP 1 LASTPIN (1075 -825) $PN 1
J 0
(1087 -813);
DISPLAY 0.787234 (1087 -813);
PAINT MONO (1087 -813);
FORCEPROP 1 LASTPIN (1275 -825) $PN 2
J 0
(1237 -813);
DISPLAY 0.787234 (1237 -813);
PAINT MONO (1237 -813);
FORCEPROP 1 LAST PATH I107
J 0
(1125 -675);
DISPLAY 0.978723 (1125 -675);
PAINT WHITE (1125 -675);
DISPLAY INVISIBLE (1125 -675);
FORCEPROP 2 LAST CDS_LIB pure_quanta
J 0
(1175 -825);
DISPLAY INVISIBLE (1175 -825);
FORCEPROP 1 LAST WATTAGE 1/16W
J 2
(1350 -700);
DISPLAY 0.638298 (1350 -700);
DISPLAY INVISIBLE (1350 -700);
FORCEPROP 0 LAST CDS_LOCATION R4758
J 0
(1125 -725);
DISPLAY 1.021277 (1125 -725);
DISPLAY INVISIBLE (1125 -725);
FORCEPROP 0 LAST $SEC 1
J 0
(1125 -725);
DISPLAY 0.680851 (1125 -725);
PAINT MONO (1125 -725);
DISPLAY INVISIBLE (1125 -725);
FORCEPROP 0 LAST CDS_SEC 1
J 0
(1125 -725);
DISPLAY 1.021277 (1125 -725);
DISPLAY INVISIBLE (1125 -725);
FORCEADD 74LVC1G08W57..1
(950 -450);
FORCEPROP 1 LAST PART_NUMBER AL1G0008020
J 0
(825 -241);
DISPLAY 0.723404 (825 -241);
PAINT GREEN (825 -241);
DISPLAY INVISIBLE (825 -241);
FORCEPROP 2 LAST PART_TYPE SMLF
J 0
(825 -25);
DISPLAY 1.021277 (825 -25);
FORCEPROP 2 LAST VALUE 74LVC1G08W5-7
J 0
(825 -175);
DISPLAY 0.808511 (825 -175);
FORCEPROP 1 LAST MATERIAL IC
J 0
(806 -293);
DISPLAY 0.723404 (806 -293);
PAINT GREEN (806 -293);
FORCEPROP 1 LAST $LOCATION U335
J 0
(825 -94);
DISPLAY 0.723404 (825 -94);
PAINT GREEN (825 -94);
FORCEPROP 2 LASTPIN (650 -350) $PN 1
J 2
(640 -340);
DISPLAY 0.680851 (640 -340);
PAINT MONO (640 -340);
FORCEPROP 2 LASTPIN (650 -450) $PN 2
J 2
(640 -440);
DISPLAY 0.680851 (640 -440);
PAINT MONO (640 -440);
FORCEPROP 2 LASTPIN (650 -550) $PN 3
J 2
(640 -540);
DISPLAY 0.680851 (640 -540);
PAINT MONO (640 -540);
FORCEPROP 2 LASTPIN (1250 -350) $PN 5
J 0
(1260 -340);
DISPLAY 0.680851 (1260 -340);
PAINT MONO (1260 -340);
FORCEPROP 2 LASTPIN (1250 -500) $PN 4
J 0
(1260 -490);
DISPLAY 0.680851 (1260 -490);
PAINT MONO (1260 -490);
FORCEPROP 1 LAST PATH I108
J 0
(950 -450);
DISPLAY 0.723404 (950 -450);
PAINT GREEN (950 -450);
DISPLAY INVISIBLE (950 -450);
FORCEPROP 2 LAST CDS_LIB pure_quanta
J 0
(950 -450);
DISPLAY INVISIBLE (950 -450);
FORCEPROP 1 LAST NEEDS_NO_SIZE TRUE
J 0
(950 -450);
DISPLAY 0.723404 (950 -450);
PAINT GREEN (950 -450);
DISPLAY INVISIBLE (950 -450);
FORCEPROP 1 LAST CDS_LMAN_SYM_OUTLINE -150,150,150,-150
J 0
(950 -450);
DISPLAY 0.468085 (950 -450);
PAINT GREEN (950 -450);
DISPLAY INVISIBLE (950 -450);
FORCEPROP 0 LAST CDS_LOCATION U335
J 0
(575 75);
DISPLAY 1.021277 (575 75);
DISPLAY INVISIBLE (575 75);
FORCEPROP 2 LAST $SEC 1
J 0
(575 75);
DISPLAY 0.680851 (575 75);
PAINT MONO (575 75);
DISPLAY INVISIBLE (575 75);
FORCEPROP 2 LAST CDS_SEC 1
J 0
(575 75);
DISPLAY 1.021277 (575 75);
DISPLAY INVISIBLE (575 75);
FORCEADD UNIVERSAL_GND..1
(1550 -425);
FORCEPROP 3 LASTPIN (1550 -375) SIG_NAME GND\g
J 0
(1560 -365);
DISPLAY 0.659574 (1560 -365);
PAINT MONO (1560 -365);
DISPLAY INVISIBLE (1560 -365);
FORCEPROP 1 LAST PATH I109
J 0
(1625 -425);
DISPLAY 0.872340 (1625 -425);
PAINT AQUA (1625 -425);
DISPLAY INVISIBLE (1625 -425);
FORCEPROP 1 LAST HDL_POWER GND
J 1
(1575 -500);
DISPLAY 0.872340 (1575 -500);
PAINT GREEN (1575 -500);
DISPLAY INVISIBLE (1575 -500);
FORCEPROP 2 LAST CDS_LIB logical_power
J 0
(1550 -425);
PAINT MONO (1550 -425);
DISPLAY INVISIBLE (1550 -425);
FORCEADD Q_CAP..1
(1550 -200);
FORCEPROP 1 LAST PART_NUMBER CH4104K1B00
J 0
(1600 -350);
DISPLAY 0.510638 (1600 -350);
DISPLAY INVISIBLE (1600 -350);
FORCEPROP 1 LAST MATERIAL X7R
J 0
(1600 -300);
DISPLAY 0.510638 (1600 -300);
FORCEPROP 1 LAST VALUE 0.1UF
J 0
(1600 -150);
DISPLAY 0.510638 (1600 -150);
FORCEPROP 1 LAST VOLTAGE 25V
J 0
(1600 -200);
DISPLAY 0.510638 (1600 -200);
FORCEPROP 1 LAST TOLERANCE 10%
J 0
(1600 -250);
DISPLAY 0.510638 (1600 -250);
FORCEPROP 1 LAST PACK_TYPE 0402
J 0
(1600 -400);
DISPLAY 0.510638 (1600 -400);
FORCEPROP 1 LAST $LOCATION C2377
J 0
(1600 -100);
DISPLAY 0.978723 (1600 -100);
FORCEPROP 1 LASTPIN (1550 -100) $PN 1
J 0
(1560 -120);
DISPLAY 0.787234 (1560 -120);
FORCEPROP 1 LASTPIN (1550 -300) $PN 2
J 0
(1560 -320);
DISPLAY 0.787234 (1560 -320);
FORCEPROP 1 LAST PATH I110
J 0
(1600 -50);
DISPLAY 0.978723 (1600 -50);
PAINT WHITE (1600 -50);
DISPLAY INVISIBLE (1600 -50);
FORCEPROP 2 LAST CDS_LIB pure_quanta
J 2
(1550 -200);
PAINT MONO (1550 -200);
DISPLAY INVISIBLE (1550 -200);
FORCEPROP 2 LAST CDS_LOCATION C2377
J 0
(1600 0);
DISPLAY 1.021277 (1600 0);
DISPLAY INVISIBLE (1600 0);
FORCEPROP 2 LAST $SEC 1
J 0
(1600 0);
DISPLAY 0.680851 (1600 0);
PAINT MONO (1600 0);
DISPLAY INVISIBLE (1600 0);
FORCEPROP 2 LAST CDS_SEC 1
J 0
(1600 0);
DISPLAY 1.021277 (1600 0);
DISPLAY INVISIBLE (1600 0);
FORCEADD Q_RES..1
(2175 -500);
FORCEPROP 1 LAST PART_NUMBER CS04992FB07
J 0
(2275 -525);
DISPLAY 0.404255 (2275 -525);
DISPLAY INVISIBLE (2275 -525);
FORCEPROP 1 LAST MATERIAL CHIP
J 0
(2025 -525);
DISPLAY 0.404255 (2025 -525);
FORCEPROP 1 LAST VALUE 49.9
J 2
(2400 -500);
DISPLAY 0.510638 (2400 -500);
FORCEPROP 1 LAST $LOCATION R4759
J 0
(1950 -500);
DISPLAY 0.638298 (1950 -500);
FORCEPROP 1 LASTPIN (2075 -500) $PN 1
J 0
(2087 -488);
DISPLAY 0.787234 (2087 -488);
PAINT MONO (2087 -488);
FORCEPROP 1 LASTPIN (2275 -500) $PN 2
J 0
(2237 -488);
DISPLAY 0.787234 (2237 -488);
PAINT MONO (2237 -488);
FORCEPROP 1 LAST PATH I111
J 0
(2125 -350);
DISPLAY 0.978723 (2125 -350);
PAINT WHITE (2125 -350);
DISPLAY INVISIBLE (2125 -350);
FORCEPROP 1 LAST WATTAGE 1/16W
J 2
(2475 -550);
DISPLAY 0.404255 (2475 -550);
DISPLAY INVISIBLE (2475 -550);
FORCEPROP 1 LAST TOLERANCE 1%
J 0
(2400 -500);
DISPLAY 0.510638 (2400 -500);
DISPLAY INVISIBLE (2400 -500);
FORCEPROP 1 LAST PACK_TYPE 0402LF
J 0
(2475 -500);
DISPLAY 0.510638 (2475 -500);
DISPLAY INVISIBLE (2475 -500);
FORCEPROP 2 LAST CDS_LIB pure_quanta
J 0
(2175 -500);
DISPLAY INVISIBLE (2175 -500);
FORCEPROP 0 LAST CDS_LOCATION R4759
J 0
(1950 -450);
DISPLAY 1.021277 (1950 -450);
DISPLAY INVISIBLE (1950 -450);
FORCEPROP 0 LAST $SEC 1
J 0
(1950 -450);
DISPLAY 0.680851 (1950 -450);
PAINT MONO (1950 -450);
DISPLAY INVISIBLE (1950 -450);
FORCEPROP 0 LAST CDS_SEC 1
J 0
(1950 -450);
DISPLAY 1.021277 (1950 -450);
DISPLAY INVISIBLE (1950 -450);
FORCEADD Q_RES..1
(1125 250);
FORCEPROP 1 LAST PART_NUMBER CS00002JB13
J 0
(1000 325);
DISPLAY 0.638298 (1000 325);
DISPLAY INVISIBLE (1000 325);
FORCEPROP 1 LAST PACK_TYPE 0402LF
J 0
(1400 250);
DISPLAY 0.638298 (1400 250);
FORCEPROP 1 LAST MATERIAL EMPTY
J 0
(1275 200);
DISPLAY 0.638298 (1275 200);
PAINT RED (1275 200);
FORCEPROP 1 LAST VALUE 0
J 2
(1300 250);
DISPLAY 0.638298 (1300 250);
FORCEPROP 1 LAST TOLERANCE 5%
J 0
(1325 250);
DISPLAY 0.638298 (1325 250);
FORCEPROP 1 LAST $LOCATION R4757
J 0
(925 250);
DISPLAY 0.638298 (925 250);
FORCEPROP 1 LASTPIN (1025 250) $PN 1
J 0
(1037 262);
DISPLAY 0.787234 (1037 262);
PAINT MONO (1037 262);
FORCEPROP 1 LASTPIN (1225 250) $PN 2
J 0
(1187 262);
DISPLAY 0.787234 (1187 262);
PAINT MONO (1187 262);
FORCEPROP 1 LAST PATH I112
J 0
(1075 400);
DISPLAY 0.978723 (1075 400);
PAINT WHITE (1075 400);
DISPLAY INVISIBLE (1075 400);
FORCEPROP 2 LAST CDS_LIB pure_quanta
J 0
(1125 250);
DISPLAY INVISIBLE (1125 250);
FORCEPROP 1 LAST WATTAGE 1/16W
J 2
(1300 375);
DISPLAY 0.638298 (1300 375);
DISPLAY INVISIBLE (1300 375);
FORCEPROP 0 LAST CDS_LOCATION R4757
J 0
(1075 350);
DISPLAY 1.021277 (1075 350);
DISPLAY INVISIBLE (1075 350);
FORCEPROP 0 LAST $SEC 1
J 0
(1075 350);
DISPLAY 0.680851 (1075 350);
PAINT MONO (1075 350);
DISPLAY INVISIBLE (1075 350);
FORCEPROP 0 LAST CDS_SEC 1
J 0
(1075 350);
DISPLAY 1.021277 (1075 350);
DISPLAY INVISIBLE (1075 350);
FORCEADD UNIVERSAL_POWER..1
(1550 75);
FORCEPROP 3 LASTPIN (1550 25) SIG_NAME P3V3_AUX\g
J 0
(1560 35);
DISPLAY 0.659574 (1560 35);
PAINT MONO (1560 35);
DISPLAY INVISIBLE (1560 35);
FORCEPROP 1 LAST HDL_POWER P3V3_AUX
J 1
(1550 125);
DISPLAY 0.872340 (1550 125);
PAINT GREEN (1550 125);
FORCEPROP 1 LAST PATH I113
J 0
(1600 100);
DISPLAY 0.872340 (1600 100);
PAINT AQUA (1600 100);
DISPLAY INVISIBLE (1600 100);
FORCEPROP 2 LAST CDS_LIB logical_power
J 0
(1550 75);
PAINT MONO (1550 75);
DISPLAY INVISIBLE (1550 75);
FORCEADD OFFPAGE..2
(3150 -500);
FORCEPROP 2 LAST $XR2 161 
J 0
(3339 -536);
DISPLAY 0.638298 (3339 -536);
PAINT MONO (3339 -536);
FORCEPROP 2 LAST $XR1 160 
J 0
(3459 -500);
DISPLAY 0.638298 (3459 -500);
PAINT MONO (3459 -500);
FORCEPROP 2 LAST $XR0 159 
J 0
(3339 -500);
DISPLAY 0.638298 (3339 -500);
PAINT MONO (3339 -500);
FORCEPROP 2 LAST PATH I115
J 0
(3475 -450);
DISPLAY 1.021277 (3475 -450);
DISPLAY INVISIBLE (3475 -450);
FORCEPROP 1 LAST OFFPAGE TRUE
J 0
(3475 -625);
DISPLAY 0.872340 (3475 -625);
PAINT GREEN (3475 -625);
DISPLAY INVISIBLE (3475 -625);
FORCEPROP 1 LAST COMMENT_BODY TRUE
J 0
(3105 -595);
DISPLAY 0.872340 (3105 -595);
PAINT GREEN (3105 -595);
DISPLAY INVISIBLE (3105 -595);
FORCEPROP 2 LAST CDS_LIB standard
J 0
(3150 -500);
DISPLAY INVISIBLE (3150 -500);
FORCEADD UNIVERSAL_GND..1
(600 -675);
FORCEPROP 3 LASTPIN (600 -625) SIG_NAME GND\g
J 0
(610 -615);
DISPLAY 0.659574 (610 -615);
PAINT MONO (610 -615);
DISPLAY INVISIBLE (610 -615);
FORCEPROP 1 LAST PATH I116
J 0
(675 -675);
DISPLAY 0.872340 (675 -675);
PAINT AQUA (675 -675);
DISPLAY INVISIBLE (675 -675);
FORCEPROP 2 LAST CDS_LIB logical_power
J 0
(600 -675);
PAINT MONO (600 -675);
DISPLAY INVISIBLE (600 -675);
FORCEPROP 1 LAST HDL_POWER GND
J 1
(625 -750);
DISPLAY 0.872340 (625 -750);
PAINT GREEN (625 -750);
DISPLAY INVISIBLE (625 -750);
FORCEADD OFFPAGE..2
(1175 1225);
FORCEPROP 2 LAST $XR1 216 
J 0
(1484 1225);
DISPLAY 0.638298 (1484 1225);
PAINT MONO (1484 1225);
FORCEPROP 2 LAST $XR0 164 
J 0
(1364 1225);
DISPLAY 0.638298 (1364 1225);
PAINT MONO (1364 1225);
FORCEPROP 2 LAST CDS_LIB standard
J 0
(1175 1225);
DISPLAY INVISIBLE (1175 1225);
FORCEPROP 2 LAST PATH I117
J 0
(1350 1300);
DISPLAY 1.021277 (1350 1300);
DISPLAY INVISIBLE (1350 1300);
FORCEPROP 1 LAST OFFPAGE TRUE
J 0
(1500 1100);
DISPLAY 0.872340 (1500 1100);
PAINT GREEN (1500 1100);
DISPLAY INVISIBLE (1500 1100);
FORCEPROP 1 LAST COMMENT_BODY TRUE
J 0
(1130 1130);
DISPLAY 0.872340 (1130 1130);
PAINT GREEN (1130 1130);
DISPLAY INVISIBLE (1130 1130);
FORCEADD UNIVERSAL_POWER..1
(-800 3975);
FORCEPROP 3 LASTPIN (-800 3925) SIG_NAME P3V3_AUX\g
J 0
(-790 3935);
DISPLAY 0.659574 (-790 3935);
PAINT MONO (-790 3935);
DISPLAY INVISIBLE (-790 3935);
FORCEPROP 1 LAST HDL_POWER P3V3_AUX
J 1
(-800 4025);
DISPLAY 0.872340 (-800 4025);
PAINT GREEN (-800 4025);
FORCEPROP 2 LAST CDS_LIB logical_power
J 0
(-800 3975);
DISPLAY INVISIBLE (-800 3975);
FORCEPROP 1 LAST PATH I118
J 0
(-750 4000);
DISPLAY 0.872340 (-750 4000);
PAINT AQUA (-750 4000);
DISPLAY INVISIBLE (-750 4000);
FORCEADD Q_RES..2
(-800 3750);
FORCEPROP 1 LAST PART_NUMBER CS31002FB08
J 0
(-760 3625);
DISPLAY 0.510638 (-760 3625);
DISPLAY INVISIBLE (-760 3625);
FORCEPROP 1 LAST MATERIAL CHIP
J 0
(-760 3675);
DISPLAY 0.510638 (-760 3675);
FORCEPROP 1 LAST TOLERANCE 1%
J 0
(-755 3775);
DISPLAY 0.510638 (-755 3775);
FORCEPROP 1 LAST WATTAGE 1/16W
J 0
(-760 3725);
DISPLAY 0.510638 (-760 3725);
FORCEPROP 1 LAST PACK_TYPE 0402LF
J 0
(-760 3575);
DISPLAY 0.510638 (-760 3575);
FORCEPROP 1 LAST VALUE 10K
J 0
(-755 3825);
DISPLAY 0.510638 (-755 3825);
FORCEPROP 1 LAST $LOCATION R4763
J 0
(-755 3875);
DISPLAY 0.978723 (-755 3875);
FORCEPROP 1 LASTPIN (-800 3850) $PN 1
J 0
(-795 3812);
DISPLAY 0.787234 (-795 3812);
PAINT MONO (-795 3812);
FORCEPROP 1 LASTPIN (-800 3650) $PN 2
J 0
(-795 3660);
DISPLAY 0.787234 (-795 3660);
PAINT MONO (-795 3660);
FORCEPROP 2 LAST CDS_LIB pure_quanta
J 0
(-800 3750);
DISPLAY INVISIBLE (-800 3750);
FORCEPROP 1 LAST PATH I119
J 0
(-750 3925);
DISPLAY 0.978723 (-750 3925);
PAINT WHITE (-750 3925);
DISPLAY INVISIBLE (-750 3925);
FORCEPROP 0 LAST CDS_LOCATION R4763
J 0
(-750 3925);
DISPLAY 1.021277 (-750 3925);
DISPLAY INVISIBLE (-750 3925);
FORCEPROP 0 LAST $SEC 1
J 0
(-750 3925);
DISPLAY 0.680851 (-750 3925);
PAINT MONO (-750 3925);
DISPLAY INVISIBLE (-750 3925);
FORCEPROP 0 LAST CDS_SEC 1
J 0
(-750 3925);
DISPLAY 1.021277 (-750 3925);
DISPLAY INVISIBLE (-750 3925);
FORCEADD UNIVERSAL_GND..1
(-2600 -875);
FORCEPROP 3 LASTPIN (-2600 -825) SIG_NAME GND\g
J 0
(-2590 -815);
DISPLAY 0.659574 (-2590 -815);
PAINT MONO (-2590 -815);
DISPLAY INVISIBLE (-2590 -815);
FORCEPROP 1 LAST HDL_POWER GND
J 1
(-2575 -950);
DISPLAY 0.872340 (-2575 -950);
PAINT GREEN (-2575 -950);
DISPLAY INVISIBLE (-2575 -950);
FORCEPROP 2 LAST CDS_LIB logical_power
J 0
(-2600 -875);
PAINT MONO (-2600 -875);
DISPLAY INVISIBLE (-2600 -875);
FORCEPROP 1 LAST PATH I14
J 0
(-2525 -875);
DISPLAY 0.872340 (-2525 -875);
PAINT AQUA (-2525 -875);
DISPLAY INVISIBLE (-2525 -875);
FORCEADD Q_CAP..1
(-2600 -650);
FORCEPROP 1 LAST PART_NUMBER CH4104K1B00
J 0
(-2550 -800);
DISPLAY 0.510638 (-2550 -800);
DISPLAY INVISIBLE (-2550 -800);
FORCEPROP 1 LAST VOLTAGE 25V
J 0
(-2550 -650);
DISPLAY 0.510638 (-2550 -650);
FORCEPROP 1 LAST MATERIAL X7R
J 0
(-2550 -750);
DISPLAY 0.510638 (-2550 -750);
FORCEPROP 1 LAST VALUE 0.1UF
J 0
(-2550 -600);
DISPLAY 0.510638 (-2550 -600);
FORCEPROP 1 LAST TOLERANCE 10%
J 0
(-2550 -700);
DISPLAY 0.510638 (-2550 -700);
FORCEPROP 1 LAST PACK_TYPE 0402
J 0
(-2550 -850);
DISPLAY 0.510638 (-2550 -850);
FORCEPROP 1 LAST $LOCATION C1818
J 0
(-2550 -550);
DISPLAY 0.978723 (-2550 -550);
FORCEPROP 1 LASTPIN (-2600 -550) $PN 1
J 0
(-2590 -570);
DISPLAY 0.787234 (-2590 -570);
FORCEPROP 1 LASTPIN (-2600 -750) $PN 2
J 0
(-2590 -770);
DISPLAY 0.787234 (-2590 -770);
FORCEPROP 2 LAST CDS_LIB pure_quanta
J 2
(-2600 -650);
PAINT MONO (-2600 -650);
DISPLAY INVISIBLE (-2600 -650);
FORCEPROP 1 LAST PATH I15
J 0
(-2550 -500);
DISPLAY 0.978723 (-2550 -500);
PAINT WHITE (-2550 -500);
DISPLAY INVISIBLE (-2550 -500);
FORCEPROP 2 LAST CDS_LOCATION C1818
J 0
(-2550 -450);
DISPLAY 1.021277 (-2550 -450);
DISPLAY INVISIBLE (-2550 -450);
FORCEPROP 2 LAST $SEC 1
J 0
(-2550 -450);
DISPLAY 0.680851 (-2550 -450);
PAINT MONO (-2550 -450);
DISPLAY INVISIBLE (-2550 -450);
FORCEPROP 2 LAST CDS_SEC 1
J 0
(-2550 -450);
DISPLAY 1.021277 (-2550 -450);
DISPLAY INVISIBLE (-2550 -450);
FORCEADD UNIVERSAL_POWER..1
(-2600 -375);
FORCEPROP 3 LASTPIN (-2600 -425) SIG_NAME P3V3_AUX\g
J 0
(-2590 -415);
DISPLAY 0.659574 (-2590 -415);
PAINT MONO (-2590 -415);
DISPLAY INVISIBLE (-2590 -415);
FORCEPROP 1 LAST HDL_POWER P3V3_AUX
J 1
(-2600 -325);
DISPLAY 0.872340 (-2600 -325);
PAINT GREEN (-2600 -325);
FORCEPROP 2 LAST CDS_LIB logical_power
J 0
(-2600 -375);
PAINT MONO (-2600 -375);
DISPLAY INVISIBLE (-2600 -375);
FORCEPROP 1 LAST PATH I16
J 0
(-2550 -350);
DISPLAY 0.872340 (-2550 -350);
PAINT AQUA (-2550 -350);
DISPLAY INVISIBLE (-2550 -350);
FORCEADD OFFPAGE..2
(-2100 -1075);
FORCEPROP 2 LAST $XR2 238 
J 0
(-1671 -1075);
DISPLAY 0.638298 (-1671 -1075);
PAINT MONO (-1671 -1075);
FORCEPROP 2 LAST $XR1 163 
J 0
(-1791 -1075);
DISPLAY 0.638298 (-1791 -1075);
PAINT MONO (-1791 -1075);
FORCEPROP 2 LAST $XR0 162 
J 0
(-1911 -1075);
DISPLAY 0.638298 (-1911 -1075);
PAINT MONO (-1911 -1075);
FORCEPROP 2 LAST CDS_LIB standard
J 0
(-2100 -1075);
PAINT MONO (-2100 -1075);
DISPLAY INVISIBLE (-2100 -1075);
FORCEPROP 1 LAST OFFPAGE TRUE
J 0
(-1775 -1200);
DISPLAY 0.872340 (-1775 -1200);
PAINT GREEN (-1775 -1200);
DISPLAY INVISIBLE (-1775 -1200);
FORCEPROP 1 LAST COMMENT_BODY TRUE
J 0
(-2145 -1170);
DISPLAY 0.872340 (-2145 -1170);
PAINT GREEN (-2145 -1170);
DISPLAY INVISIBLE (-2145 -1170);
FORCEPROP 2 LAST PATH I17
J 0
(-1900 -1025);
DISPLAY 1.021277 (-1900 -1025);
DISPLAY INVISIBLE (-1900 -1025);
FORCEADD OFFPAGE..2
(-1550 2075);
FORCEPROP 2 LAST $XR0 235 
J 0
(-1331 2075);
DISPLAY 0.638298 (-1331 2075);
PAINT MONO (-1331 2075);
FORCEPROP 1 LAST COMMENT_BODY TRUE
J 0
(-1595 1980);
DISPLAY 0.872340 (-1595 1980);
PAINT GREEN (-1595 1980);
DISPLAY INVISIBLE (-1595 1980);
FORCEPROP 1 LAST OFFPAGE TRUE
J 0
(-1225 1950);
DISPLAY 0.872340 (-1225 1950);
PAINT GREEN (-1225 1950);
DISPLAY INVISIBLE (-1225 1950);
FORCEPROP 2 LAST CDS_LIB standard
J 0
(-1550 2075);
DISPLAY INVISIBLE (-1550 2075);
FORCEPROP 2 LAST PATH I18
J 0
(-1325 2125);
DISPLAY 1.021277 (-1325 2125);
DISPLAY INVISIBLE (-1325 2125);
FORCEADD OFFPAGE..1
(-4300 2075);
FORCEPROP 2 LAST $XR0 164 
J 0
(-4612 2075);
DISPLAY 0.638298 (-4612 2075);
PAINT MONO (-4612 2075);
FORCEPROP 1 LAST COMMENT_BODY TRUE
J 0
(-4175 1975);
DISPLAY 0.872340 (-4175 1975);
PAINT GREEN (-4175 1975);
DISPLAY INVISIBLE (-4175 1975);
FORCEPROP 1 LAST OFFPAGE TRUE
J 0
(-3975 1950);
DISPLAY 0.872340 (-3975 1950);
PAINT GREEN (-3975 1950);
DISPLAY INVISIBLE (-3975 1950);
FORCEPROP 2 LAST CDS_LIB standard
J 0
(-4300 2075);
DISPLAY INVISIBLE (-4300 2075);
FORCEPROP 2 LAST PATH I2
J 0
(-4575 2125);
DISPLAY 1.021277 (-4575 2125);
DISPLAY INVISIBLE (-4575 2125);
FORCEADD Q_RES..1
(-3150 2075);
FORCEPROP 1 LAST PART_NUMBER CS03322FB03
J 0
(-3275 2125);
DISPLAY 0.638298 (-3275 2125);
DISPLAY INVISIBLE (-3275 2125);
FORCEPROP 1 LAST PACK_TYPE 0402LF
J 0
(-2825 2075);
DISPLAY 0.510638 (-2825 2075);
FORCEPROP 1 LAST VALUE 33.2
J 2
(-2950 2075);
DISPLAY 0.510638 (-2950 2075);
FORCEPROP 1 LAST TOLERANCE 1%
J 0
(-2925 2075);
DISPLAY 0.510638 (-2925 2075);
FORCEPROP 1 LAST $LOCATION R3158
J 0
(-3400 2075);
DISPLAY 0.638298 (-3400 2075);
FORCEPROP 1 LASTPIN (-3250 2075) $PN 1
J 0
(-3238 2087);
DISPLAY 0.787234 (-3238 2087);
PAINT MONO (-3238 2087);
FORCEPROP 1 LASTPIN (-3050 2075) $PN 2
J 0
(-3088 2087);
DISPLAY 0.787234 (-3088 2087);
PAINT MONO (-3088 2087);
FORCEPROP 1 LAST WATTAGE 1/16W
J 2
(-2950 2175);
DISPLAY 0.638298 (-2950 2175);
DISPLAY INVISIBLE (-2950 2175);
FORCEPROP 1 LAST MATERIAL CHIP
J 0
(-3275 2175);
DISPLAY 0.638298 (-3275 2175);
DISPLAY INVISIBLE (-3275 2175);
FORCEPROP 1 LAST PATH I23
J 0
(-3200 2225);
DISPLAY 0.978723 (-3200 2225);
PAINT WHITE (-3200 2225);
DISPLAY INVISIBLE (-3200 2225);
FORCEPROP 2 LAST CDS_LIB pure_quanta
J 0
(-3150 2075);
DISPLAY INVISIBLE (-3150 2075);
FORCEPROP 0 LAST CDS_LOCATION R3158
J 0
(-3400 2125);
DISPLAY 1.021277 (-3400 2125);
DISPLAY INVISIBLE (-3400 2125);
FORCEPROP 0 LAST $SEC 1
J 0
(-3400 2125);
DISPLAY 0.680851 (-3400 2125);
PAINT MONO (-3400 2125);
DISPLAY INVISIBLE (-3400 2125);
FORCEPROP 0 LAST CDS_SEC 1
J 0
(-3400 2125);
DISPLAY 1.021277 (-3400 2125);
DISPLAY INVISIBLE (-3400 2125);
FORCEADD UNIVERSAL_GND..1
(-5175 2650);
FORCEPROP 3 LASTPIN (-5175 2700) SIG_NAME GND\g
J 0
(-5165 2710);
DISPLAY 0.659574 (-5165 2710);
PAINT MONO (-5165 2710);
DISPLAY INVISIBLE (-5165 2710);
FORCEPROP 2 LAST CDS_LIB logical_power
J 0
(-5175 2650);
PAINT MONO (-5175 2650);
DISPLAY INVISIBLE (-5175 2650);
FORCEPROP 1 LAST HDL_POWER GND
J 1
(-5150 2575);
DISPLAY 0.872340 (-5150 2575);
PAINT GREEN (-5150 2575);
DISPLAY INVISIBLE (-5150 2575);
FORCEPROP 1 LAST PATH I24
J 0
(-5100 2650);
DISPLAY 0.872340 (-5100 2650);
PAINT AQUA (-5100 2650);
DISPLAY INVISIBLE (-5100 2650);
FORCEADD Q_RES..2
(-5175 2875);
FORCEPROP 1 LAST PART_NUMBER CS21002FB06
J 0
(-5135 2700);
DISPLAY 0.638298 (-5135 2700);
DISPLAY INVISIBLE (-5135 2700);
FORCEPROP 1 LAST TOLERANCE 1%
J 0
(-5130 2900);
DISPLAY 0.638298 (-5130 2900);
FORCEPROP 1 LAST WATTAGE 1/16W
J 0
(-5135 2850);
DISPLAY 0.638298 (-5135 2850);
FORCEPROP 1 LAST MATERIAL CHIP
J 0
(-5135 2800);
DISPLAY 0.638298 (-5135 2800);
FORCEPROP 1 LAST VALUE 1K
J 0
(-5130 2950);
DISPLAY 0.638298 (-5130 2950);
FORCEPROP 1 LAST PACK_TYPE 0402LF
J 0
(-5135 2750);
DISPLAY 0.638298 (-5135 2750);
FORCEPROP 1 LAST $LOCATION R3150
J 0
(-5130 3000);
DISPLAY 0.978723 (-5130 3000);
FORCEPROP 1 LASTPIN (-5175 2975) $PN 1
J 0
(-5170 2937);
DISPLAY 0.787234 (-5170 2937);
FORCEPROP 1 LASTPIN (-5175 2775) $PN 2
J 0
(-5170 2785);
DISPLAY 0.787234 (-5170 2785);
FORCEPROP 2 LAST CDS_LIB pure_quanta
J 0
(-5175 2875);
PAINT MONO (-5175 2875);
DISPLAY INVISIBLE (-5175 2875);
FORCEPROP 1 LAST PATH I25
J 0
(-5125 3050);
DISPLAY 0.978723 (-5125 3050);
PAINT WHITE (-5125 3050);
DISPLAY INVISIBLE (-5125 3050);
FORCEPROP 2 LAST CDS_LOCATION R3150
J 0
(-5125 3100);
DISPLAY 1.021277 (-5125 3100);
DISPLAY INVISIBLE (-5125 3100);
FORCEPROP 2 LAST $SEC 1
J 0
(-5125 3100);
DISPLAY 0.680851 (-5125 3100);
PAINT MONO (-5125 3100);
DISPLAY INVISIBLE (-5125 3100);
FORCEPROP 2 LAST CDS_SEC 1
J 0
(-5125 3100);
DISPLAY 1.021277 (-5125 3100);
DISPLAY INVISIBLE (-5125 3100);
FORCEADD UNIVERSAL_GND..1
(-4925 2650);
FORCEPROP 3 LASTPIN (-4925 2700) SIG_NAME GND\g
J 0
(-4915 2710);
DISPLAY 0.659574 (-4915 2710);
PAINT MONO (-4915 2710);
DISPLAY INVISIBLE (-4915 2710);
FORCEPROP 2 LAST CDS_LIB logical_power
J 0
(-4925 2650);
PAINT MONO (-4925 2650);
DISPLAY INVISIBLE (-4925 2650);
FORCEPROP 1 LAST HDL_POWER GND
J 1
(-4900 2575);
DISPLAY 0.872340 (-4900 2575);
PAINT GREEN (-4900 2575);
DISPLAY INVISIBLE (-4900 2575);
FORCEPROP 1 LAST PATH I26
J 0
(-4850 2650);
DISPLAY 0.872340 (-4850 2650);
PAINT AQUA (-4850 2650);
DISPLAY INVISIBLE (-4850 2650);
FORCEADD Q_RES..2
(-4925 2875);
FORCEPROP 1 LAST PART_NUMBER CS21002FB06
J 0
(-4885 2700);
DISPLAY 0.638298 (-4885 2700);
DISPLAY INVISIBLE (-4885 2700);
FORCEPROP 1 LAST TOLERANCE 1%
J 0
(-4880 2900);
DISPLAY 0.638298 (-4880 2900);
FORCEPROP 1 LAST MATERIAL CHIP
J 0
(-4885 2800);
DISPLAY 0.638298 (-4885 2800);
FORCEPROP 1 LAST VALUE 1K
J 0
(-4880 2950);
DISPLAY 0.638298 (-4880 2950);
FORCEPROP 1 LAST WATTAGE 1/16W
J 0
(-4885 2850);
DISPLAY 0.638298 (-4885 2850);
FORCEPROP 1 LAST PACK_TYPE 0402LF
J 0
(-4885 2750);
DISPLAY 0.638298 (-4885 2750);
FORCEPROP 1 LAST $LOCATION R3152
J 0
(-4880 3000);
DISPLAY 0.978723 (-4880 3000);
FORCEPROP 1 LASTPIN (-4925 2975) $PN 1
J 0
(-4920 2937);
DISPLAY 0.787234 (-4920 2937);
FORCEPROP 1 LASTPIN (-4925 2775) $PN 2
J 0
(-4920 2785);
DISPLAY 0.787234 (-4920 2785);
FORCEPROP 2 LAST CDS_LIB pure_quanta
J 0
(-4925 2875);
PAINT MONO (-4925 2875);
DISPLAY INVISIBLE (-4925 2875);
FORCEPROP 1 LAST PATH I27
J 0
(-4875 3050);
DISPLAY 0.978723 (-4875 3050);
PAINT WHITE (-4875 3050);
DISPLAY INVISIBLE (-4875 3050);
FORCEPROP 2 LAST CDS_LOCATION R3152
J 0
(-4875 3100);
DISPLAY 1.021277 (-4875 3100);
DISPLAY INVISIBLE (-4875 3100);
FORCEPROP 2 LAST $SEC 1
J 0
(-4875 3100);
DISPLAY 0.680851 (-4875 3100);
PAINT MONO (-4875 3100);
DISPLAY INVISIBLE (-4875 3100);
FORCEPROP 2 LAST CDS_SEC 1
J 0
(-4875 3100);
DISPLAY 1.021277 (-4875 3100);
DISPLAY INVISIBLE (-4875 3100);
FORCEADD UNIVERSAL_GND..1
(-4675 2650);
FORCEPROP 3 LASTPIN (-4675 2700) SIG_NAME GND\g
J 0
(-4665 2710);
DISPLAY 0.659574 (-4665 2710);
PAINT MONO (-4665 2710);
DISPLAY INVISIBLE (-4665 2710);
FORCEPROP 2 LAST CDS_LIB logical_power
J 0
(-4675 2650);
PAINT MONO (-4675 2650);
DISPLAY INVISIBLE (-4675 2650);
FORCEPROP 1 LAST HDL_POWER GND
J 1
(-4650 2575);
DISPLAY 0.872340 (-4650 2575);
PAINT GREEN (-4650 2575);
DISPLAY INVISIBLE (-4650 2575);
FORCEPROP 1 LAST PATH I28
J 0
(-4600 2650);
DISPLAY 0.872340 (-4600 2650);
PAINT AQUA (-4600 2650);
DISPLAY INVISIBLE (-4600 2650);
FORCEADD Q_RES..2
(-5175 3475);
FORCEPROP 1 LAST PART_NUMBER CS21002FB06
J 0
(-5135 3300);
DISPLAY 0.638298 (-5135 3300);
DISPLAY INVISIBLE (-5135 3300);
FORCEPROP 1 LAST TOLERANCE 1%
J 0
(-5130 3500);
DISPLAY 0.638298 (-5130 3500);
FORCEPROP 1 LAST VALUE 1K
J 0
(-5130 3550);
DISPLAY 0.638298 (-5130 3550);
FORCEPROP 1 LAST WATTAGE 1/16W
J 0
(-5135 3450);
DISPLAY 0.638298 (-5135 3450);
FORCEPROP 1 LAST PACK_TYPE 0402LF
J 0
(-5135 3350);
DISPLAY 0.638298 (-5135 3350);
FORCEPROP 1 LAST MATERIAL EMPTY
J 0
(-5135 3400);
DISPLAY 0.638298 (-5135 3400);
PAINT RED (-5135 3400);
FORCEPROP 1 LAST $LOCATION R3149
J 0
(-5130 3600);
DISPLAY 0.978723 (-5130 3600);
FORCEPROP 1 LASTPIN (-5175 3575) $PN 1
J 0
(-5170 3537);
DISPLAY 0.787234 (-5170 3537);
FORCEPROP 1 LASTPIN (-5175 3375) $PN 2
J 0
(-5170 3385);
DISPLAY 0.787234 (-5170 3385);
FORCEPROP 2 LAST CDS_LIB pure_quanta
J 0
(-5175 3475);
PAINT MONO (-5175 3475);
DISPLAY INVISIBLE (-5175 3475);
FORCEPROP 1 LAST PATH I29
J 0
(-5125 3650);
DISPLAY 0.978723 (-5125 3650);
PAINT WHITE (-5125 3650);
DISPLAY INVISIBLE (-5125 3650);
FORCEPROP 2 LAST CDS_LOCATION R3149
J 0
(-5125 3700);
DISPLAY 1.021277 (-5125 3700);
DISPLAY INVISIBLE (-5125 3700);
FORCEPROP 2 LAST $SEC 1
J 0
(-5125 3700);
DISPLAY 0.680851 (-5125 3700);
PAINT MONO (-5125 3700);
DISPLAY INVISIBLE (-5125 3700);
FORCEPROP 2 LAST CDS_SEC 1
J 0
(-5125 3700);
DISPLAY 1.021277 (-5125 3700);
DISPLAY INVISIBLE (-5125 3700);
FORCEADD MOSFET_N..1
(-4300 -1250);
FORCEPROP 1 LAST PART_NUMBER BAM138K0000
J 0
(-4178 -1364);
DISPLAY 0.574468 (-4178 -1364);
PAINT GREEN (-4178 -1364);
DISPLAY INVISIBLE (-4178 -1364);
FORCEPROP 2 LAST PATH I3
J 0
(-4175 -1200);
DISPLAY 1.021277 (-4175 -1200);
FORCEPROP 1 LAST VALUE BSS138K
J 0
(-4178 -1229);
DISPLAY 0.574468 (-4178 -1229);
PAINT GREEN (-4178 -1229);
FORCEPROP 1 LAST MATERIAL IC
J 0
(-4178 -1419);
DISPLAY 0.574468 (-4178 -1419);
PAINT GREEN (-4178 -1419);
FORCEPROP 1 LAST $LOCATION U215
J 0
(-4178 -1309);
DISPLAY 0.574468 (-4178 -1309);
PAINT GREEN (-4178 -1309);
FORCEPROP 1 LASTPIN (-4250 -1150) $PN D
R 1
J 0
(-4250 -1157);
DISPLAY 0.659574 (-4250 -1157);
PAINT GREEN (-4250 -1157);
FORCEPROP 1 LASTPIN (-4400 -1350) $PN G
J 2
(-4390 -1347);
DISPLAY 0.659574 (-4390 -1347);
PAINT GREEN (-4390 -1347);
FORCEPROP 1 LASTPIN (-4250 -1450) $PN S
R 1
J 2
(-4250 -1437);
DISPLAY 0.659574 (-4250 -1437);
PAINT GREEN (-4250 -1437);
FORCEPROP 0 LAST MANUF_PN BSS138K
J 0
(-4175 -1125);
DISPLAY 0.510638 (-4175 -1125);
DISPLAY INVISIBLE (-4175 -1125);
FORCEPROP 1 LAST CDS_LMAN_SYM_OUTLINE -50,50,100,-150
J 0
(-4300 -1250);
DISPLAY 0.468085 (-4300 -1250);
PAINT GREEN (-4300 -1250);
DISPLAY INVISIBLE (-4300 -1250);
FORCEPROP 2 LAST CDS_LIB pure_quanta
J 0
(-4300 -1250);
PAINT MONO (-4300 -1250);
DISPLAY INVISIBLE (-4300 -1250);
FORCEPROP 1 LAST PACK_TYPE SMLF
J 0
(-4275 -1500);
DISPLAY 0.723404 (-4275 -1500);
PAINT GREEN (-4275 -1500);
DISPLAY INVISIBLE (-4275 -1500);
FORCEPROP 2 LAST CDS_LOCATION U215
J 0
(-4175 -1100);
DISPLAY 1.021277 (-4175 -1100);
DISPLAY INVISIBLE (-4175 -1100);
FORCEPROP 2 LAST $SEC 1
J 0
(-4175 -1100);
DISPLAY 0.680851 (-4175 -1100);
PAINT MONO (-4175 -1100);
DISPLAY INVISIBLE (-4175 -1100);
FORCEPROP 2 LAST CDS_SEC 1
J 0
(-4175 -1100);
DISPLAY 1.021277 (-4175 -1100);
DISPLAY INVISIBLE (-4175 -1100);
FORCEADD UNIVERSAL_POWER..1
(-5175 3875);
FORCEPROP 3 LASTPIN (-5175 3825) SIG_NAME P3V3_AUX\g
J 0
(-5165 3835);
DISPLAY 0.659574 (-5165 3835);
PAINT MONO (-5165 3835);
DISPLAY INVISIBLE (-5165 3835);
FORCEPROP 1 LAST HDL_POWER P3V3_AUX
J 1
(-5175 3925);
DISPLAY 0.872340 (-5175 3925);
PAINT GREEN (-5175 3925);
FORCEPROP 2 LAST CDS_LIB logical_power
J 0
(-5175 3875);
PAINT MONO (-5175 3875);
DISPLAY INVISIBLE (-5175 3875);
FORCEPROP 1 LAST PATH I30
J 0
(-5125 3900);
DISPLAY 0.872340 (-5125 3900);
PAINT AQUA (-5125 3900);
DISPLAY INVISIBLE (-5125 3900);
FORCEADD Q_RES..2
(-4925 3475);
FORCEPROP 1 LAST PART_NUMBER CS21002FB06
J 0
(-4885 3300);
DISPLAY 0.638298 (-4885 3300);
DISPLAY INVISIBLE (-4885 3300);
FORCEPROP 1 LAST VALUE 1K
J 0
(-4880 3550);
DISPLAY 0.638298 (-4880 3550);
FORCEPROP 1 LAST TOLERANCE 1%
J 0
(-4880 3500);
DISPLAY 0.638298 (-4880 3500);
FORCEPROP 1 LAST WATTAGE 1/16W
J 0
(-4885 3450);
DISPLAY 0.638298 (-4885 3450);
FORCEPROP 1 LAST MATERIAL EMPTY
J 0
(-4885 3400);
DISPLAY 0.638298 (-4885 3400);
PAINT RED (-4885 3400);
FORCEPROP 1 LAST PACK_TYPE 0402LF
J 0
(-4885 3350);
DISPLAY 0.638298 (-4885 3350);
FORCEPROP 1 LAST $LOCATION R3151
J 0
(-4880 3600);
DISPLAY 0.978723 (-4880 3600);
FORCEPROP 1 LASTPIN (-4925 3575) $PN 1
J 0
(-4920 3537);
DISPLAY 0.787234 (-4920 3537);
FORCEPROP 1 LASTPIN (-4925 3375) $PN 2
J 0
(-4920 3385);
DISPLAY 0.787234 (-4920 3385);
FORCEPROP 2 LAST CDS_LIB pure_quanta
J 0
(-4925 3475);
PAINT MONO (-4925 3475);
DISPLAY INVISIBLE (-4925 3475);
FORCEPROP 1 LAST PATH I31
J 0
(-4875 3650);
DISPLAY 0.978723 (-4875 3650);
PAINT WHITE (-4875 3650);
DISPLAY INVISIBLE (-4875 3650);
FORCEPROP 2 LAST CDS_LOCATION R3151
J 0
(-4875 3700);
DISPLAY 1.021277 (-4875 3700);
DISPLAY INVISIBLE (-4875 3700);
FORCEPROP 2 LAST $SEC 1
J 0
(-4875 3700);
DISPLAY 0.680851 (-4875 3700);
PAINT MONO (-4875 3700);
DISPLAY INVISIBLE (-4875 3700);
FORCEPROP 2 LAST CDS_SEC 1
J 0
(-4875 3700);
DISPLAY 1.021277 (-4875 3700);
DISPLAY INVISIBLE (-4875 3700);
FORCEADD Q_RES..2
(-4675 3475);
FORCEPROP 1 LAST PART_NUMBER CS21002FB06
J 0
(-4635 3300);
DISPLAY 0.638298 (-4635 3300);
DISPLAY INVISIBLE (-4635 3300);
FORCEPROP 1 LAST WATTAGE 1/16W
J 0
(-4635 3450);
DISPLAY 0.638298 (-4635 3450);
FORCEPROP 1 LAST TOLERANCE 1%
J 0
(-4630 3500);
DISPLAY 0.638298 (-4630 3500);
FORCEPROP 1 LAST VALUE 1K
J 0
(-4630 3550);
DISPLAY 0.638298 (-4630 3550);
FORCEPROP 1 LAST MATERIAL EMPTY
J 0
(-4635 3400);
DISPLAY 0.638298 (-4635 3400);
PAINT RED (-4635 3400);
FORCEPROP 1 LAST PACK_TYPE 0402LF
J 0
(-4635 3350);
DISPLAY 0.638298 (-4635 3350);
FORCEPROP 1 LAST $LOCATION R3153
J 0
(-4630 3600);
DISPLAY 0.978723 (-4630 3600);
FORCEPROP 1 LASTPIN (-4675 3575) $PN 1
J 0
(-4670 3537);
DISPLAY 0.787234 (-4670 3537);
FORCEPROP 1 LASTPIN (-4675 3375) $PN 2
J 0
(-4670 3385);
DISPLAY 0.787234 (-4670 3385);
FORCEPROP 2 LAST CDS_LIB pure_quanta
J 0
(-4675 3475);
PAINT MONO (-4675 3475);
DISPLAY INVISIBLE (-4675 3475);
FORCEPROP 1 LAST PATH I32
J 0
(-4625 3650);
DISPLAY 0.978723 (-4625 3650);
PAINT WHITE (-4625 3650);
DISPLAY INVISIBLE (-4625 3650);
FORCEPROP 2 LAST CDS_LOCATION R3153
J 0
(-4625 3700);
DISPLAY 1.021277 (-4625 3700);
DISPLAY INVISIBLE (-4625 3700);
FORCEPROP 2 LAST $SEC 1
J 0
(-4625 3700);
DISPLAY 0.680851 (-4625 3700);
PAINT MONO (-4625 3700);
DISPLAY INVISIBLE (-4625 3700);
FORCEPROP 2 LAST CDS_SEC 1
J 0
(-4625 3700);
DISPLAY 1.021277 (-4625 3700);
DISPLAY INVISIBLE (-4625 3700);
FORCEADD Q_RES..1
(-3150 2125);
FORCEPROP 1 LAST PART_NUMBER CS03322FB03
J 0
(-3275 2175);
DISPLAY 0.638298 (-3275 2175);
DISPLAY INVISIBLE (-3275 2175);
FORCEPROP 1 LAST PACK_TYPE 0402LF
J 0
(-2825 2125);
DISPLAY 0.510638 (-2825 2125);
FORCEPROP 1 LAST VALUE 33.2
J 2
(-2950 2125);
DISPLAY 0.510638 (-2950 2125);
FORCEPROP 1 LAST TOLERANCE 1%
J 0
(-2925 2125);
DISPLAY 0.510638 (-2925 2125);
FORCEPROP 1 LAST $LOCATION R3157
J 0
(-3400 2125);
DISPLAY 0.638298 (-3400 2125);
FORCEPROP 1 LASTPIN (-3250 2125) $PN 1
J 0
(-3238 2137);
DISPLAY 0.787234 (-3238 2137);
FORCEPROP 1 LASTPIN (-3050 2125) $PN 2
J 0
(-3088 2137);
DISPLAY 0.787234 (-3088 2137);
FORCEPROP 2 LAST CDS_LIB pure_quanta
J 0
(-3150 2125);
PAINT MONO (-3150 2125);
DISPLAY INVISIBLE (-3150 2125);
FORCEPROP 1 LAST WATTAGE 1/16W
J 2
(-2950 2225);
DISPLAY 0.638298 (-2950 2225);
DISPLAY INVISIBLE (-2950 2225);
FORCEPROP 1 LAST MATERIAL CHIP
J 0
(-3275 2225);
DISPLAY 0.638298 (-3275 2225);
DISPLAY INVISIBLE (-3275 2225);
FORCEPROP 1 LAST PATH I33
J 0
(-3200 2275);
DISPLAY 0.978723 (-3200 2275);
PAINT WHITE (-3200 2275);
DISPLAY INVISIBLE (-3200 2275);
FORCEPROP 2 LAST CDS_LOCATION R3157
J 0
(-3200 2325);
DISPLAY 1.021277 (-3200 2325);
DISPLAY INVISIBLE (-3200 2325);
FORCEPROP 2 LAST $SEC 1
J 0
(-3200 2325);
DISPLAY 0.680851 (-3200 2325);
PAINT MONO (-3200 2325);
DISPLAY INVISIBLE (-3200 2325);
FORCEPROP 2 LAST CDS_SEC 1
J 0
(-3200 2325);
DISPLAY 1.021277 (-3200 2325);
DISPLAY INVISIBLE (-3200 2325);
FORCEADD Q_RES..1
(-3150 2175);
FORCEPROP 1 LAST PART_NUMBER CS03322FB03
J 0
(-3275 2225);
DISPLAY 0.638298 (-3275 2225);
DISPLAY INVISIBLE (-3275 2225);
FORCEPROP 1 LAST WATTAGE 1/16W
J 2
(-2950 2275);
DISPLAY 0.638298 (-2950 2275);
FORCEPROP 1 LAST VALUE 33.2
J 2
(-2950 2175);
DISPLAY 0.510638 (-2950 2175);
FORCEPROP 1 LAST PACK_TYPE 0402LF
J 0
(-2825 2175);
DISPLAY 0.510638 (-2825 2175);
FORCEPROP 1 LAST TOLERANCE 1%
J 0
(-2925 2175);
DISPLAY 0.510638 (-2925 2175);
FORCEPROP 1 LAST MATERIAL CHIP
J 0
(-3275 2275);
DISPLAY 0.638298 (-3275 2275);
FORCEPROP 1 LAST $LOCATION R3156
J 0
(-3400 2175);
DISPLAY 0.638298 (-3400 2175);
FORCEPROP 1 LASTPIN (-3250 2175) $PN 1
J 0
(-3238 2187);
DISPLAY 0.787234 (-3238 2187);
FORCEPROP 1 LASTPIN (-3050 2175) $PN 2
J 0
(-3088 2187);
DISPLAY 0.787234 (-3088 2187);
FORCEPROP 2 LAST CDS_LIB pure_quanta
J 0
(-3150 2175);
PAINT MONO (-3150 2175);
DISPLAY INVISIBLE (-3150 2175);
FORCEPROP 1 LAST PATH I34
J 0
(-3200 2325);
DISPLAY 0.978723 (-3200 2325);
PAINT WHITE (-3200 2325);
DISPLAY INVISIBLE (-3200 2325);
FORCEPROP 2 LAST CDS_LOCATION R3156
J 0
(-3200 2375);
DISPLAY 1.021277 (-3200 2375);
DISPLAY INVISIBLE (-3200 2375);
FORCEPROP 2 LAST $SEC 1
J 0
(-3200 2375);
DISPLAY 0.680851 (-3200 2375);
PAINT MONO (-3200 2375);
DISPLAY INVISIBLE (-3200 2375);
FORCEPROP 2 LAST CDS_SEC 1
J 0
(-3200 2375);
DISPLAY 1.021277 (-3200 2375);
DISPLAY INVISIBLE (-3200 2375);
FORCEADD OFFPAGE..2
R 2
(-3200 3325);
FORCEPROP 2 LAST $XR0 164 
J 0
(-3485 3325);
DISPLAY 0.638298 (-3485 3325);
PAINT MONO (-3485 3325);
FORCEPROP 1 LAST COMMENT_BODY TRUE
J 2
(-3155 3230);
DISPLAY 0.872340 (-3155 3230);
PAINT GREEN (-3155 3230);
DISPLAY INVISIBLE (-3155 3230);
FORCEPROP 1 LAST OFFPAGE TRUE
J 2
(-3525 3200);
DISPLAY 0.872340 (-3525 3200);
PAINT GREEN (-3525 3200);
DISPLAY INVISIBLE (-3525 3200);
FORCEPROP 2 LAST CDS_LIB standard
J 2
(-3200 3325);
DISPLAY INVISIBLE (-3200 3325);
FORCEPROP 2 LAST PATH I37
J 0
(-3475 3375);
DISPLAY 1.021277 (-3475 3375);
DISPLAY INVISIBLE (-3475 3375);
FORCEADD UNIVERSAL_GND..1
(-2825 3550);
FORCEPROP 3 LASTPIN (-2825 3600) SIG_NAME GND\g
J 0
(-2815 3610);
DISPLAY 0.659574 (-2815 3610);
PAINT MONO (-2815 3610);
DISPLAY INVISIBLE (-2815 3610);
FORCEPROP 1 LAST HDL_POWER GND
J 1
(-2800 3475);
DISPLAY 0.872340 (-2800 3475);
PAINT GREEN (-2800 3475);
DISPLAY INVISIBLE (-2800 3475);
FORCEPROP 2 LAST CDS_LIB logical_power
J 0
(-2825 3550);
PAINT MONO (-2825 3550);
DISPLAY INVISIBLE (-2825 3550);
FORCEPROP 1 LAST PATH I38
J 0
(-2750 3550);
DISPLAY 0.872340 (-2750 3550);
PAINT AQUA (-2750 3550);
DISPLAY INVISIBLE (-2750 3550);
FORCEADD Q_CAP..1
(-2825 3775);
FORCEPROP 1 LAST PART_NUMBER CH4104K1B00
J 0
(-2775 3625);
DISPLAY 0.510638 (-2775 3625);
DISPLAY INVISIBLE (-2775 3625);
FORCEPROP 1 LAST TOLERANCE 10%
J 0
(-2775 3725);
DISPLAY 0.510638 (-2775 3725);
FORCEPROP 1 LAST MATERIAL X7R
J 0
(-2775 3675);
DISPLAY 0.510638 (-2775 3675);
FORCEPROP 1 LAST VOLTAGE 25V
J 0
(-2775 3775);
DISPLAY 0.510638 (-2775 3775);
FORCEPROP 1 LAST VALUE 0.1UF
J 0
(-2775 3825);
DISPLAY 0.510638 (-2775 3825);
FORCEPROP 1 LAST PACK_TYPE 0402
J 0
(-2775 3575);
DISPLAY 0.510638 (-2775 3575);
FORCEPROP 1 LAST $LOCATION C1817
J 0
(-2775 3875);
DISPLAY 0.978723 (-2775 3875);
FORCEPROP 1 LASTPIN (-2825 3875) $PN 1
J 0
(-2815 3855);
DISPLAY 0.787234 (-2815 3855);
FORCEPROP 1 LASTPIN (-2825 3675) $PN 2
J 0
(-2815 3655);
DISPLAY 0.787234 (-2815 3655);
FORCEPROP 2 LAST CDS_LIB pure_quanta
J 0
(-2825 3775);
PAINT MONO (-2825 3775);
DISPLAY INVISIBLE (-2825 3775);
FORCEPROP 1 LAST PATH I39
J 0
(-2775 3925);
DISPLAY 0.978723 (-2775 3925);
PAINT WHITE (-2775 3925);
DISPLAY INVISIBLE (-2775 3925);
FORCEPROP 2 LAST CDS_LOCATION C1817
J 2
(-2775 3975);
DISPLAY 1.021277 (-2775 3975);
DISPLAY INVISIBLE (-2775 3975);
FORCEPROP 2 LAST $SEC 1
J 2
(-2775 3975);
DISPLAY 0.680851 (-2775 3975);
PAINT MONO (-2775 3975);
DISPLAY INVISIBLE (-2775 3975);
FORCEPROP 2 LAST CDS_SEC 1
J 2
(-2775 3975);
DISPLAY 1.021277 (-2775 3975);
DISPLAY INVISIBLE (-2775 3975);
FORCEADD UNIVERSAL_GND..1
(-4250 -1625);
FORCEPROP 3 LASTPIN (-4250 -1575) SIG_NAME GND\g
J 0
(-4240 -1565);
DISPLAY 0.659574 (-4240 -1565);
PAINT MONO (-4240 -1565);
DISPLAY INVISIBLE (-4240 -1565);
FORCEPROP 1 LAST HDL_POWER GND
J 1
(-4225 -1700);
DISPLAY 0.872340 (-4225 -1700);
PAINT GREEN (-4225 -1700);
DISPLAY INVISIBLE (-4225 -1700);
FORCEPROP 2 LAST CDS_LIB logical_power
J 0
(-4250 -1625);
PAINT MONO (-4250 -1625);
DISPLAY INVISIBLE (-4250 -1625);
FORCEPROP 1 LAST PATH I4
J 0
(-4175 -1625);
DISPLAY 0.872340 (-4175 -1625);
PAINT AQUA (-4175 -1625);
DISPLAY INVISIBLE (-4175 -1625);
FORCEADD UNIVERSAL_POWER..1
(-2825 4050);
FORCEPROP 3 LASTPIN (-2825 4000) SIG_NAME P3V3_AUX\g
J 0
(-2815 4010);
DISPLAY 0.659574 (-2815 4010);
PAINT MONO (-2815 4010);
DISPLAY INVISIBLE (-2815 4010);
FORCEPROP 1 LAST HDL_POWER P3V3_AUX
J 1
(-2825 4100);
DISPLAY 0.872340 (-2825 4100);
PAINT GREEN (-2825 4100);
FORCEPROP 2 LAST CDS_LIB logical_power
J 0
(-2825 4050);
PAINT MONO (-2825 4050);
DISPLAY INVISIBLE (-2825 4050);
FORCEPROP 1 LAST PATH I40
J 0
(-2775 4075);
DISPLAY 0.872340 (-2775 4075);
PAINT AQUA (-2775 4075);
DISPLAY INVISIBLE (-2775 4075);
FORCEADD UNIVERSAL_GND..1
(-2250 2500);
FORCEPROP 3 LASTPIN (-2250 2550) SIG_NAME GND\g
J 0
(-2240 2560);
DISPLAY 0.659574 (-2240 2560);
PAINT MONO (-2240 2560);
DISPLAY INVISIBLE (-2240 2560);
FORCEPROP 1 LAST PATH I41
J 0
(-2175 2500);
DISPLAY 0.872340 (-2175 2500);
PAINT AQUA (-2175 2500);
DISPLAY INVISIBLE (-2175 2500);
FORCEPROP 2 LAST CDS_LIB logical_power
J 0
(-2250 2500);
PAINT MONO (-2250 2500);
DISPLAY INVISIBLE (-2250 2500);
FORCEPROP 1 LAST HDL_POWER GND
J 1
(-2225 2425);
DISPLAY 0.872340 (-2225 2425);
PAINT GREEN (-2225 2425);
DISPLAY INVISIBLE (-2225 2425);
FORCEADD OFFPAGE..2
(-1550 2175);
FORCEPROP 2 LAST $XR0 164 
J 0
(-1361 2175);
DISPLAY 0.638298 (-1361 2175);
PAINT MONO (-1361 2175);
FORCEPROP 1 LAST COMMENT_BODY TRUE
J 0
(-1595 2080);
DISPLAY 0.872340 (-1595 2080);
PAINT GREEN (-1595 2080);
DISPLAY INVISIBLE (-1595 2080);
FORCEPROP 1 LAST OFFPAGE TRUE
J 0
(-1225 2050);
DISPLAY 0.872340 (-1225 2050);
PAINT GREEN (-1225 2050);
DISPLAY INVISIBLE (-1225 2050);
FORCEPROP 2 LAST CDS_LIB standard
J 0
(-1550 2175);
PAINT MONO (-1550 2175);
DISPLAY INVISIBLE (-1550 2175);
FORCEPROP 2 LAST PATH I42
J 0
(-1350 2225);
DISPLAY 1.021277 (-1350 2225);
DISPLAY INVISIBLE (-1350 2225);
FORCEADD OFFPAGE..3
(-1550 2125);
FORCEPROP 2 LAST $XR0 164 
J 0
(-1336 2125);
DISPLAY 0.638298 (-1336 2125);
PAINT MONO (-1336 2125);
FORCEPROP 2 LAST CDS_LIB standard
J 0
(-1550 2125);
PAINT MONO (-1550 2125);
DISPLAY INVISIBLE (-1550 2125);
FORCEPROP 1 LAST OFFPAGE TRUE
J 0
(-1225 2000);
DISPLAY 0.872340 (-1225 2000);
PAINT GREEN (-1225 2000);
DISPLAY INVISIBLE (-1225 2000);
FORCEPROP 1 LAST COMMENT_BODY TRUE
J 0
(-1600 2025);
DISPLAY 0.872340 (-1600 2025);
PAINT GREEN (-1600 2025);
DISPLAY INVISIBLE (-1600 2025);
FORCEPROP 2 LAST PATH I43
J 0
(-1325 2175);
DISPLAY 1.021277 (-1325 2175);
DISPLAY INVISIBLE (-1325 2175);
FORCEADD OFFPAGE..1
R 2
(-350 3325);
FORCEPROP 2 LAST $XR0 162 
J 0
(-164 3325);
DISPLAY 0.638298 (-164 3325);
PAINT MONO (-164 3325);
FORCEPROP 2 LAST CDS_LIB standard
J 2
(-350 3325);
PAINT MONO (-350 3325);
DISPLAY INVISIBLE (-350 3325);
FORCEPROP 1 LAST OFFPAGE TRUE
J 2
(-675 3200);
DISPLAY 0.872340 (-675 3200);
PAINT GREEN (-675 3200);
DISPLAY INVISIBLE (-675 3200);
FORCEPROP 1 LAST COMMENT_BODY TRUE
J 2
(-475 3225);
DISPLAY 0.872340 (-475 3225);
PAINT GREEN (-475 3225);
DISPLAY INVISIBLE (-475 3225);
FORCEPROP 2 LAST PATH I44
J 0
(-150 3375);
DISPLAY 1.021277 (-150 3375);
DISPLAY INVISIBLE (-150 3375);
FORCEADD OFFPAGE..1
R 2
(-350 3275);
FORCEPROP 2 LAST $XR1 164 
J 0
(-44 3275);
DISPLAY 0.638298 (-44 3275);
PAINT MONO (-44 3275);
FORCEPROP 2 LAST $XR0 162 
J 0
(-164 3275);
DISPLAY 0.638298 (-164 3275);
PAINT MONO (-164 3275);
FORCEPROP 1 LAST OFFPAGE TRUE
J 2
(-675 3150);
DISPLAY 1.170213 (-675 3150);
PAINT GREEN (-675 3150);
DISPLAY INVISIBLE (-675 3150);
FORCEPROP 1 LAST COMMENT_BODY TRUE
J 2
(-475 3175);
DISPLAY 1.170213 (-475 3175);
PAINT GREEN (-475 3175);
DISPLAY INVISIBLE (-475 3175);
FORCEPROP 2 LAST CDS_LIB standard
J 0
(-350 3275);
PAINT MONO (-350 3275);
DISPLAY INVISIBLE (-350 3275);
FORCEPROP 2 LAST PATH I45
J 0
(-25 3325);
DISPLAY 1.021277 (-25 3325);
DISPLAY INVISIBLE (-25 3325);
FORCEADD OFFPAGE..1
R 2
(-350 3225);
FORCEPROP 1 LAST OFFPAGE TRUE
J 2
(-675 3100);
DISPLAY 1.170213 (-675 3100);
PAINT GREEN (-675 3100);
DISPLAY INVISIBLE (-675 3100);
FORCEPROP 1 LAST COMMENT_BODY TRUE
J 2
(-475 3125);
DISPLAY 1.170213 (-475 3125);
PAINT GREEN (-475 3125);
DISPLAY INVISIBLE (-475 3125);
FORCEPROP 2 LAST CDS_LIB standard
J 0
(-350 3225);
PAINT MONO (-350 3225);
DISPLAY INVISIBLE (-350 3225);
FORCEPROP 2 LAST PATH I46
J 0
(-150 3275);
DISPLAY 1.021277 (-150 3275);
DISPLAY INVISIBLE (-150 3275);
FORCEADD OFFPAGE..2
(-350 3375);
FORCEPROP 2 LAST $XR0 164 
J 0
(-161 3375);
DISPLAY 0.638298 (-161 3375);
PAINT MONO (-161 3375);
FORCEPROP 2 LAST CDS_LIB standard
J 0
(-350 3375);
DISPLAY INVISIBLE (-350 3375);
FORCEPROP 1 LAST OFFPAGE TRUE
J 0
(-25 3250);
DISPLAY 0.872340 (-25 3250);
PAINT GREEN (-25 3250);
DISPLAY INVISIBLE (-25 3250);
FORCEPROP 1 LAST COMMENT_BODY TRUE
J 0
(-395 3280);
DISPLAY 0.872340 (-395 3280);
PAINT GREEN (-395 3280);
DISPLAY INVISIBLE (-395 3280);
FORCEPROP 2 LAST PATH I47
J 0
(-150 3425);
DISPLAY 1.021277 (-150 3425);
DISPLAY INVISIBLE (-150 3425);
FORCEADD UNIVERSAL_GND..1
(-3475 -1250);
FORCEPROP 3 LASTPIN (-3475 -1200) SIG_NAME GND\g
J 0
(-3465 -1190);
DISPLAY 0.659574 (-3465 -1190);
PAINT MONO (-3465 -1190);
DISPLAY INVISIBLE (-3465 -1190);
FORCEPROP 1 LAST HDL_POWER GND
J 1
(-3450 -1325);
DISPLAY 0.872340 (-3450 -1325);
PAINT GREEN (-3450 -1325);
DISPLAY INVISIBLE (-3450 -1325);
FORCEPROP 2 LAST CDS_LIB logical_power
J 0
(-3475 -1250);
PAINT MONO (-3475 -1250);
DISPLAY INVISIBLE (-3475 -1250);
FORCEPROP 1 LAST PATH I5
J 0
(-3400 -1250);
DISPLAY 0.872340 (-3400 -1250);
PAINT AQUA (-3400 -1250);
DISPLAY INVISIBLE (-3400 -1250);
FORCEADD OFFPAGE..1
(825 850);
FORCEPROP 2 LAST $XR0 223 
J 0
(573 850);
DISPLAY 0.638298 (573 850);
PAINT MONO (573 850);
FORCEPROP 2 LAST PATH I50
J 0
(575 900);
DISPLAY 1.021277 (575 900);
DISPLAY INVISIBLE (575 900);
FORCEPROP 1 LAST OFFPAGE TRUE
J 0
(1150 725);
DISPLAY 0.872340 (1150 725);
PAINT GREEN (1150 725);
DISPLAY INVISIBLE (1150 725);
FORCEPROP 1 LAST COMMENT_BODY TRUE
J 0
(950 750);
DISPLAY 0.872340 (950 750);
PAINT GREEN (950 750);
DISPLAY INVISIBLE (950 750);
FORCEPROP 2 LAST CDS_LIB standard
J 0
(825 850);
PAINT MONO (825 850);
DISPLAY INVISIBLE (825 850);
FORCEADD UNIVERSAL_GND..1
(1725 625);
FORCEPROP 3 LASTPIN (1725 675) SIG_NAME GND\g
J 0
(1735 685);
DISPLAY 0.659574 (1735 685);
PAINT MONO (1735 685);
DISPLAY INVISIBLE (1735 685);
FORCEPROP 1 LAST PATH I55
J 0
(1800 625);
DISPLAY 0.872340 (1800 625);
PAINT AQUA (1800 625);
DISPLAY INVISIBLE (1800 625);
FORCEPROP 1 LAST HDL_POWER GND
J 1
(1750 550);
DISPLAY 0.872340 (1750 550);
PAINT GREEN (1750 550);
DISPLAY INVISIBLE (1750 550);
FORCEPROP 2 LAST CDS_LIB logical_power
J 0
(1725 625);
PAINT MONO (1725 625);
DISPLAY INVISIBLE (1725 625);
FORCEADD 74LVC1G08W57..1
(2075 850);
FORCEPROP 1 LAST PART_NUMBER AL1G0008020
J 0
(1931 1134);
DISPLAY 0.723404 (1931 1134);
PAINT GREEN (1931 1134);
DISPLAY INVISIBLE (1931 1134);
FORCEPROP 2 LAST VALUE 74LVC1G08W5-7
J 0
(1675 1200);
DISPLAY 1.021277 (1675 1200);
FORCEPROP 1 LAST MATERIAL IC
J 0
(1931 1007);
DISPLAY 0.723404 (1931 1007);
PAINT GREEN (1931 1007);
FORCEPROP 2 LAST PART_TYPE SMLF
J 0
(1700 1325);
DISPLAY 1.021277 (1700 1325);
FORCEPROP 1 LAST LOCATION U53
J 0
(1931 1281);
DISPLAY 0.723404 (1931 1281);
PAINT GREEN (1931 1281);
FORCEPROP 2 LASTPIN (1775 950) $PN 1
J 2
(1765 960);
DISPLAY 0.680851 (1765 960);
PAINT MONO (1765 960);
FORCEPROP 2 LASTPIN (1775 850) $PN 2
J 2
(1765 860);
DISPLAY 0.680851 (1765 860);
PAINT MONO (1765 860);
FORCEPROP 2 LASTPIN (1775 750) $PN 3
J 2
(1765 760);
DISPLAY 0.680851 (1765 760);
PAINT MONO (1765 760);
FORCEPROP 2 LASTPIN (2375 950) $PN 5
J 0
(2385 960);
DISPLAY 0.680851 (2385 960);
PAINT MONO (2385 960);
FORCEPROP 2 LASTPIN (2375 800) $PN 4
J 0
(2385 810);
DISPLAY 0.680851 (2385 810);
PAINT MONO (2385 810);
FORCEPROP 1 LAST CDS_LMAN_SYM_OUTLINE -150,150,150,-150
J 0
(2075 850);
DISPLAY 0.468085 (2075 850);
PAINT GREEN (2075 850);
DISPLAY INVISIBLE (2075 850);
FORCEPROP 1 LAST NEEDS_NO_SIZE TRUE
J 0
(2075 850);
DISPLAY 0.723404 (2075 850);
PAINT GREEN (2075 850);
DISPLAY INVISIBLE (2075 850);
FORCEPROP 2 LAST CDS_LIB pure_quanta
J 0
(2075 850);
DISPLAY INVISIBLE (2075 850);
FORCEPROP 1 LAST PATH I56
J 0
(2075 850);
DISPLAY 0.723404 (2075 850);
PAINT GREEN (2075 850);
DISPLAY INVISIBLE (2075 850);
FORCEPROP 2 LAST $SEC 1
J 0
(1700 1375);
DISPLAY 0.680851 (1700 1375);
PAINT MONO (1700 1375);
DISPLAY INVISIBLE (1700 1375);
FORCEPROP 2 LAST CDS_SEC 1
J 0
(1700 1375);
DISPLAY 1.021277 (1700 1375);
DISPLAY INVISIBLE (1700 1375);
FORCEADD UNIVERSAL_GND..1
(2625 1125);
FORCEPROP 3 LASTPIN (2625 1175) SIG_NAME GND\g
J 0
(2635 1185);
DISPLAY 0.659574 (2635 1185);
PAINT MONO (2635 1185);
DISPLAY INVISIBLE (2635 1185);
FORCEPROP 1 LAST HDL_POWER GND
J 1
(2650 1050);
DISPLAY 0.872340 (2650 1050);
PAINT GREEN (2650 1050);
DISPLAY INVISIBLE (2650 1050);
FORCEPROP 2 LAST CDS_LIB logical_power
J 0
(2625 1125);
PAINT MONO (2625 1125);
DISPLAY INVISIBLE (2625 1125);
FORCEPROP 1 LAST PATH I57
J 0
(2700 1125);
DISPLAY 0.872340 (2700 1125);
PAINT AQUA (2700 1125);
DISPLAY INVISIBLE (2700 1125);
FORCEADD Q_CAP..1
(2625 1350);
FORCEPROP 1 LAST PART_NUMBER CH4104K1B00
J 0
(2675 1200);
DISPLAY 0.510638 (2675 1200);
DISPLAY INVISIBLE (2675 1200);
FORCEPROP 1 LAST MATERIAL X7R
J 0
(2675 1250);
DISPLAY 0.510638 (2675 1250);
FORCEPROP 1 LAST TOLERANCE 10%
J 0
(2675 1300);
DISPLAY 0.510638 (2675 1300);
FORCEPROP 1 LAST VOLTAGE 25V
J 0
(2675 1350);
DISPLAY 0.510638 (2675 1350);
FORCEPROP 1 LAST VALUE 0.1UF
J 0
(2675 1400);
DISPLAY 0.510638 (2675 1400);
FORCEPROP 1 LAST PACK_TYPE 0402
J 0
(2675 1150);
DISPLAY 0.510638 (2675 1150);
FORCEPROP 1 LAST $LOCATION C1820
J 0
(2675 1450);
DISPLAY 0.978723 (2675 1450);
FORCEPROP 1 LASTPIN (2625 1450) $PN 1
J 0
(2635 1430);
DISPLAY 0.787234 (2635 1430);
FORCEPROP 1 LASTPIN (2625 1250) $PN 2
J 0
(2635 1230);
DISPLAY 0.787234 (2635 1230);
FORCEPROP 2 LAST CDS_LIB pure_quanta
J 2
(2625 1350);
PAINT MONO (2625 1350);
DISPLAY INVISIBLE (2625 1350);
FORCEPROP 1 LAST PATH I58
J 0
(2675 1500);
DISPLAY 0.978723 (2675 1500);
PAINT WHITE (2675 1500);
DISPLAY INVISIBLE (2675 1500);
FORCEPROP 2 LAST CDS_LOCATION C1820
J 0
(2675 1550);
DISPLAY 1.021277 (2675 1550);
DISPLAY INVISIBLE (2675 1550);
FORCEPROP 2 LAST $SEC 1
J 0
(2675 1550);
DISPLAY 0.680851 (2675 1550);
PAINT MONO (2675 1550);
DISPLAY INVISIBLE (2675 1550);
FORCEPROP 2 LAST CDS_SEC 1
J 0
(2675 1550);
DISPLAY 1.021277 (2675 1550);
DISPLAY INVISIBLE (2675 1550);
FORCEADD UNIVERSAL_POWER..1
(2625 1625);
FORCEPROP 3 LASTPIN (2625 1575) SIG_NAME P3V3_AUX\g
J 0
(2635 1585);
DISPLAY 0.659574 (2635 1585);
PAINT MONO (2635 1585);
DISPLAY INVISIBLE (2635 1585);
FORCEPROP 1 LAST HDL_POWER P3V3_AUX
J 1
(2625 1675);
DISPLAY 0.872340 (2625 1675);
PAINT GREEN (2625 1675);
FORCEPROP 2 LAST CDS_LIB logical_power
J 0
(2625 1625);
PAINT MONO (2625 1625);
DISPLAY INVISIBLE (2625 1625);
FORCEPROP 1 LAST PATH I59
J 0
(2675 1650);
DISPLAY 0.872340 (2675 1650);
PAINT AQUA (2675 1650);
DISPLAY INVISIBLE (2675 1650);
FORCEADD OFFPAGE..1
(-3950 -925);
FORCEPROP 2 LAST $XR0 164 
J 0
(-4232 -925);
DISPLAY 0.638298 (-4232 -925);
PAINT MONO (-4232 -925);
FORCEPROP 2 LAST PATH I6
J 0
(-4200 -875);
DISPLAY 1.021277 (-4200 -875);
DISPLAY INVISIBLE (-4200 -875);
FORCEPROP 1 LAST OFFPAGE TRUE
J 0
(-3625 -1050);
DISPLAY 0.872340 (-3625 -1050);
PAINT GREEN (-3625 -1050);
DISPLAY INVISIBLE (-3625 -1050);
FORCEPROP 1 LAST COMMENT_BODY TRUE
J 0
(-3825 -1025);
DISPLAY 0.872340 (-3825 -1025);
PAINT GREEN (-3825 -1025);
DISPLAY INVISIBLE (-3825 -1025);
FORCEPROP 2 LAST CDS_LIB standard
J 0
(-3950 -925);
PAINT MONO (-3950 -925);
DISPLAY INVISIBLE (-3950 -925);
FORCEADD OFFPAGE..2
(3150 800);
FORCEPROP 2 LAST $XR0 161 
J 0
(3339 800);
DISPLAY 0.638298 (3339 800);
PAINT MONO (3339 800);
FORCEPROP 1 LAST COMMENT_BODY TRUE
J 0
(3105 705);
DISPLAY 0.872340 (3105 705);
PAINT GREEN (3105 705);
DISPLAY INVISIBLE (3105 705);
FORCEPROP 1 LAST OFFPAGE TRUE
J 0
(3475 675);
DISPLAY 0.872340 (3475 675);
PAINT GREEN (3475 675);
DISPLAY INVISIBLE (3475 675);
FORCEPROP 2 LAST PATH I60
J 0
(3350 850);
DISPLAY 1.021277 (3350 850);
DISPLAY INVISIBLE (3350 850);
FORCEPROP 2 LAST CDS_LIB standard
J 0
(3150 800);
PAINT MONO (3150 800);
DISPLAY INVISIBLE (3150 800);
FORCEADD OFFPAGE..3
R 2
(-4300 2125);
FORCEPROP 2 LAST $XR0 235 
J 0
(-4610 2125);
DISPLAY 0.638298 (-4610 2125);
PAINT MONO (-4610 2125);
FORCEPROP 1 LAST OFFPAGE TRUE
J 2
(-4625 2000);
DISPLAY 0.872340 (-4625 2000);
DISPLAY INVISIBLE (-4625 2000);
FORCEPROP 1 LAST COMMENT_BODY TRUE
J 2
(-4250 2025);
DISPLAY 0.872340 (-4250 2025);
PAINT GREEN (-4250 2025);
DISPLAY INVISIBLE (-4250 2025);
FORCEPROP 2 LAST CDS_LIB standard
J 0
(-4300 2125);
PAINT MONO (-4300 2125);
DISPLAY INVISIBLE (-4300 2125);
FORCEPROP 2 LAST PATH I63
J 0
(-4600 2175);
DISPLAY 1.021277 (-4600 2175);
DISPLAY INVISIBLE (-4600 2175);
FORCEADD OFFPAGE..1
(-4300 2175);
FORCEPROP 2 LAST $XR0 235 
J 0
(-4552 2175);
DISPLAY 0.638298 (-4552 2175);
PAINT MONO (-4552 2175);
FORCEPROP 2 LAST CDS_LIB standard
J 0
(-4300 2175);
PAINT MONO (-4300 2175);
DISPLAY INVISIBLE (-4300 2175);
FORCEPROP 1 LAST OFFPAGE TRUE
J 0
(-3975 2050);
DISPLAY 0.872340 (-3975 2050);
PAINT GREEN (-3975 2050);
DISPLAY INVISIBLE (-3975 2050);
FORCEPROP 1 LAST COMMENT_BODY TRUE
J 0
(-4175 2075);
DISPLAY 0.872340 (-4175 2075);
PAINT GREEN (-4175 2075);
DISPLAY INVISIBLE (-4175 2075);
FORCEPROP 2 LAST PATH I64
J 0
(-4575 2225);
DISPLAY 1.021277 (-4575 2225);
DISPLAY INVISIBLE (-4575 2225);
FORCEADD Q_RES..2
(-4675 2875);
FORCEPROP 1 LAST PART_NUMBER CS21002FB06
J 0
(-4635 2700);
DISPLAY 0.638298 (-4635 2700);
DISPLAY INVISIBLE (-4635 2700);
FORCEPROP 1 LAST TOLERANCE 1%
J 0
(-4630 2900);
DISPLAY 0.638298 (-4630 2900);
FORCEPROP 1 LAST MATERIAL CHIP
J 0
(-4635 2800);
DISPLAY 0.638298 (-4635 2800);
FORCEPROP 1 LAST WATTAGE 1/16W
J 0
(-4635 2850);
DISPLAY 0.638298 (-4635 2850);
FORCEPROP 1 LAST VALUE 1K
J 0
(-4630 2950);
DISPLAY 0.638298 (-4630 2950);
FORCEPROP 1 LAST PACK_TYPE 0402LF
J 0
(-4635 2750);
DISPLAY 0.638298 (-4635 2750);
FORCEPROP 1 LAST $LOCATION R3154
J 0
(-4630 3000);
DISPLAY 0.978723 (-4630 3000);
FORCEPROP 1 LASTPIN (-4675 2975) $PN 1
J 0
(-4670 2937);
DISPLAY 0.787234 (-4670 2937);
FORCEPROP 1 LASTPIN (-4675 2775) $PN 2
J 0
(-4670 2785);
DISPLAY 0.787234 (-4670 2785);
FORCEPROP 2 LAST CDS_LIB pure_quanta
J 0
(-4675 2875);
PAINT MONO (-4675 2875);
DISPLAY INVISIBLE (-4675 2875);
FORCEPROP 1 LAST PATH I65
J 0
(-4625 3050);
DISPLAY 0.978723 (-4625 3050);
PAINT WHITE (-4625 3050);
DISPLAY INVISIBLE (-4625 3050);
FORCEPROP 2 LAST CDS_LOCATION R3154
J 0
(-4625 3100);
DISPLAY 1.021277 (-4625 3100);
DISPLAY INVISIBLE (-4625 3100);
FORCEPROP 2 LAST $SEC 1
J 0
(-4625 3100);
DISPLAY 0.680851 (-4625 3100);
PAINT MONO (-4625 3100);
DISPLAY INVISIBLE (-4625 3100);
FORCEPROP 2 LAST CDS_SEC 1
J 0
(-4625 3100);
DISPLAY 1.021277 (-4625 3100);
DISPLAY INVISIBLE (-4625 3100);
FORCEADD PCA9555APW..1
(-1775 3125);
FORCEPROP 1 LAST PART_NUMBER AL009555K07
J 0
(-1998 3765);
DISPLAY 0.723404 (-1998 3765);
PAINT GREEN (-1998 3765);
DISPLAY INVISIBLE (-1998 3765);
FORCEPROP 2 LAST PART_TYPE SMLF
J 0
(-1975 4000);
DISPLAY 1.021277 (-1975 4000);
FORCEPROP 1 LAST MATERIAL IC
J 0
(-1998 3638);
DISPLAY 0.723404 (-1998 3638);
PAINT GREEN (-1998 3638);
FORCEPROP 2 LAST VALUE PCA9555APW
J 0
(-1975 3950);
DISPLAY 1.021277 (-1975 3950);
FORCEPROP 1 LAST LOCATION U51
J 0
(-1998 3912);
DISPLAY 0.723404 (-1998 3912);
PAINT GREEN (-1998 3912);
FORCEPROP 0 LASTPIN (-2150 3225) $PN 21
J 2
(-2160 3235);
DISPLAY 0.680851 (-2160 3235);
PAINT MONO (-2160 3235);
FORCEPROP 0 LASTPIN (-2150 3175) $PN 2
J 2
(-2160 3185);
DISPLAY 0.680851 (-2160 3185);
PAINT MONO (-2160 3185);
FORCEPROP 0 LASTPIN (-2150 3125) $PN 3
J 2
(-2160 3135);
DISPLAY 0.680851 (-2160 3135);
PAINT MONO (-2160 3135);
FORCEPROP 0 LASTPIN (-2150 3325) $PN 1
J 2
(-2160 3335);
DISPLAY 0.680851 (-2160 3335);
PAINT MONO (-2160 3335);
FORCEPROP 0 LASTPIN (-1400 3475) $PN 4
J 0
(-1390 3485);
DISPLAY 0.680851 (-1390 3485);
PAINT MONO (-1390 3485);
FORCEPROP 0 LASTPIN (-1400 3425) $PN 5
J 0
(-1390 3435);
DISPLAY 0.680851 (-1390 3435);
PAINT MONO (-1390 3435);
FORCEPROP 0 LASTPIN (-1400 3375) $PN 6
J 0
(-1390 3385);
DISPLAY 0.680851 (-1390 3385);
PAINT MONO (-1390 3385);
FORCEPROP 0 LASTPIN (-1400 3325) $PN 7
J 0
(-1390 3335);
DISPLAY 0.680851 (-1390 3335);
PAINT MONO (-1390 3335);
FORCEPROP 0 LASTPIN (-1400 3275) $PN 8
J 0
(-1390 3285);
DISPLAY 0.680851 (-1390 3285);
PAINT MONO (-1390 3285);
FORCEPROP 0 LASTPIN (-1400 3225) $PN 9
J 0
(-1390 3235);
DISPLAY 0.680851 (-1390 3235);
PAINT MONO (-1390 3235);
FORCEPROP 0 LASTPIN (-1400 3175) $PN 10
J 0
(-1390 3185);
DISPLAY 0.680851 (-1390 3185);
PAINT MONO (-1390 3185);
FORCEPROP 0 LASTPIN (-1400 3125) $PN 11
J 0
(-1390 3135);
DISPLAY 0.680851 (-1390 3135);
PAINT MONO (-1390 3135);
FORCEPROP 0 LASTPIN (-1400 3075) $PN 13
J 0
(-1390 3085);
DISPLAY 0.680851 (-1390 3085);
PAINT MONO (-1390 3085);
FORCEPROP 0 LASTPIN (-1400 3025) $PN 14
J 0
(-1390 3035);
DISPLAY 0.680851 (-1390 3035);
PAINT MONO (-1390 3035);
FORCEPROP 0 LASTPIN (-1400 2975) $PN 15
J 0
(-1390 2985);
DISPLAY 0.680851 (-1390 2985);
PAINT MONO (-1390 2985);
FORCEPROP 0 LASTPIN (-1400 2925) $PN 16
J 0
(-1390 2935);
DISPLAY 0.680851 (-1390 2935);
PAINT MONO (-1390 2935);
FORCEPROP 0 LASTPIN (-1400 2875) $PN 17
J 0
(-1390 2885);
DISPLAY 0.680851 (-1390 2885);
PAINT MONO (-1390 2885);
FORCEPROP 0 LASTPIN (-1400 2825) $PN 18
J 0
(-1390 2835);
DISPLAY 0.680851 (-1390 2835);
PAINT MONO (-1390 2835);
FORCEPROP 0 LASTPIN (-1400 2775) $PN 19
J 0
(-1390 2785);
DISPLAY 0.680851 (-1390 2785);
PAINT MONO (-1390 2785);
FORCEPROP 0 LASTPIN (-1400 2725) $PN 20
J 0
(-1390 2735);
DISPLAY 0.680851 (-1390 2735);
PAINT MONO (-1390 2735);
FORCEPROP 0 LASTPIN (-2150 2875) $PN 22
J 2
(-2160 2885);
DISPLAY 0.680851 (-2160 2885);
PAINT MONO (-2160 2885);
FORCEPROP 0 LASTPIN (-2150 2975) $PN 23
J 2
(-2160 2985);
DISPLAY 0.680851 (-2160 2985);
PAINT MONO (-2160 2985);
FORCEPROP 0 LASTPIN (-2150 3525) $PN 24
J 2
(-2160 3535);
DISPLAY 0.680851 (-2160 3535);
PAINT MONO (-2160 3535);
FORCEPROP 0 LASTPIN (-2150 2725) $PN 12
J 2
(-2160 2735);
DISPLAY 0.680851 (-2160 2735);
PAINT MONO (-2160 2735);
FORCEPROP 2 LAST CDS_LIB pure_quanta
J 0
(-1775 3125);
DISPLAY INVISIBLE (-1775 3125);
FORCEPROP 1 LAST PATH I66
J 0
(-1775 3125);
DISPLAY 0.723404 (-1775 3125);
PAINT GREEN (-1775 3125);
DISPLAY INVISIBLE (-1775 3125);
FORCEPROP 1 LAST CDS_LMAN_SYM_OUTLINE -225,500,225,-500
J 0
(-1775 3125);
DISPLAY 0.468085 (-1775 3125);
PAINT GREEN (-1775 3125);
DISPLAY INVISIBLE (-1775 3125);
FORCEPROP 1 LAST NEEDS_NO_SIZE TRUE
J 0
(-1775 3125);
DISPLAY 0.723404 (-1775 3125);
PAINT GREEN (-1775 3125);
DISPLAY INVISIBLE (-1775 3125);
FORCEPROP 0 LAST $SEC 1
J 0
(-1975 4050);
DISPLAY 0.680851 (-1975 4050);
PAINT MONO (-1975 4050);
DISPLAY INVISIBLE (-1975 4050);
FORCEPROP 0 LAST CDS_SEC 1
J 0
(-1975 4050);
DISPLAY 1.021277 (-1975 4050);
DISPLAY INVISIBLE (-1975 4050);
FORCEADD OFFPAGE..6
(-3200 2975);
FORCEPROP 2 LAST $XR0 164 
J 0
(-3480 2975);
DISPLAY 0.638298 (-3480 2975);
PAINT MONO (-3480 2975);
FORCEPROP 2 LAST PATH I67
J 0
(-3475 3025);
DISPLAY 1.021277 (-3475 3025);
DISPLAY INVISIBLE (-3475 3025);
FORCEPROP 1 LAST COMMENT_BODY TRUE
J 0
(-3100 2900);
DISPLAY 0.872340 (-3100 2900);
PAINT GREEN (-3100 2900);
DISPLAY INVISIBLE (-3100 2900);
FORCEPROP 1 LAST OFFPAGE TRUE
J 0
(-2875 2850);
DISPLAY 0.872340 (-2875 2850);
DISPLAY INVISIBLE (-2875 2850);
FORCEPROP 2 LAST CDS_LIB standard
J 2
(-3200 2975);
DISPLAY INVISIBLE (-3200 2975);
FORCEADD OFFPAGE..1
(-3200 2875);
FORCEPROP 2 LAST $XR0 164 
J 0
(-3452 2875);
DISPLAY 0.638298 (-3452 2875);
PAINT MONO (-3452 2875);
FORCEPROP 2 LAST PATH I68
J 0
(-3450 2925);
DISPLAY 1.021277 (-3450 2925);
DISPLAY INVISIBLE (-3450 2925);
FORCEPROP 1 LAST OFFPAGE TRUE
J 0
(-2875 2750);
DISPLAY 1.170213 (-2875 2750);
PAINT GREEN (-2875 2750);
DISPLAY INVISIBLE (-2875 2750);
FORCEPROP 1 LAST COMMENT_BODY TRUE
J 0
(-3075 2775);
DISPLAY 1.170213 (-3075 2775);
PAINT GREEN (-3075 2775);
DISPLAY INVISIBLE (-3075 2775);
FORCEPROP 2 LAST CDS_LIB standard
J 2
(-3200 2875);
PAINT MONO (-3200 2875);
DISPLAY INVISIBLE (-3200 2875);
FORCEADD Q_RES..2
(-4250 -700);
FORCEPROP 1 LAST PART_NUMBER CS21002FB06
J 0
(-4210 -875);
DISPLAY 0.638298 (-4210 -875);
DISPLAY INVISIBLE (-4210 -875);
FORCEPROP 1 LAST WATTAGE 1/16W
J 0
(-4210 -725);
DISPLAY 0.638298 (-4210 -725);
FORCEPROP 1 LAST TOLERANCE 1%
J 0
(-4205 -675);
DISPLAY 0.638298 (-4205 -675);
FORCEPROP 1 LAST MATERIAL CHIP
J 0
(-4210 -775);
DISPLAY 0.638298 (-4210 -775);
FORCEPROP 1 LAST PACK_TYPE 0402LF
J 0
(-4210 -825);
DISPLAY 0.638298 (-4210 -825);
FORCEPROP 1 LAST VALUE 1K
J 0
(-4205 -625);
DISPLAY 0.638298 (-4205 -625);
FORCEPROP 1 LAST $LOCATION R3155
J 0
(-4205 -575);
DISPLAY 0.978723 (-4205 -575);
FORCEPROP 1 LASTPIN (-4250 -600) $PN 1
J 0
(-4245 -638);
DISPLAY 0.787234 (-4245 -638);
FORCEPROP 1 LASTPIN (-4250 -800) $PN 2
J 0
(-4245 -790);
DISPLAY 0.787234 (-4245 -790);
FORCEPROP 2 LAST CDS_LIB pure_quanta
J 0
(-4250 -700);
PAINT MONO (-4250 -700);
DISPLAY INVISIBLE (-4250 -700);
FORCEPROP 1 LAST PATH I7
J 0
(-4200 -525);
DISPLAY 0.978723 (-4200 -525);
PAINT WHITE (-4200 -525);
DISPLAY INVISIBLE (-4200 -525);
FORCEPROP 2 LAST CDS_LOCATION R3155
J 0
(-4200 -475);
DISPLAY 1.021277 (-4200 -475);
DISPLAY INVISIBLE (-4200 -475);
FORCEPROP 2 LAST $SEC 1
J 0
(-4200 -475);
DISPLAY 0.680851 (-4200 -475);
PAINT MONO (-4200 -475);
DISPLAY INVISIBLE (-4200 -475);
FORCEPROP 2 LAST CDS_SEC 1
J 0
(-4200 -475);
DISPLAY 1.021277 (-4200 -475);
DISPLAY INVISIBLE (-4200 -475);
FORCEADD UNIVERSAL_POWER..1
(-4250 -425);
FORCEPROP 3 LASTPIN (-4250 -475) SIG_NAME P3V3_AUX\g
J 0
(-4240 -465);
DISPLAY 0.659574 (-4240 -465);
PAINT MONO (-4240 -465);
DISPLAY INVISIBLE (-4240 -465);
FORCEPROP 1 LAST HDL_POWER P3V3_AUX
J 1
(-4250 -375);
DISPLAY 0.872340 (-4250 -375);
PAINT GREEN (-4250 -375);
FORCEPROP 2 LAST CDS_LIB logical_power
J 0
(-4250 -425);
PAINT MONO (-4250 -425);
DISPLAY INVISIBLE (-4250 -425);
FORCEPROP 1 LAST PATH I8
J 0
(-4200 -400);
DISPLAY 0.872340 (-4200 -400);
PAINT AQUA (-4200 -400);
DISPLAY INVISIBLE (-4200 -400);
FORCEADD UNIVERSAL_GND..1
(-4500 800);
FORCEPROP 3 LASTPIN (-4500 850) SIG_NAME GND\g
J 0
(-4490 860);
DISPLAY 0.659574 (-4490 860);
PAINT MONO (-4490 860);
DISPLAY INVISIBLE (-4490 860);
FORCEPROP 1 LAST PATH I81
J 0
(-4425 800);
DISPLAY 0.872340 (-4425 800);
PAINT AQUA (-4425 800);
DISPLAY INVISIBLE (-4425 800);
FORCEPROP 1 LAST HDL_POWER GND
J 1
(-4475 725);
DISPLAY 0.872340 (-4475 725);
PAINT GREEN (-4475 725);
DISPLAY INVISIBLE (-4475 725);
FORCEPROP 2 LAST CDS_LIB logical_power
J 0
(-4500 800);
PAINT MONO (-4500 800);
DISPLAY INVISIBLE (-4500 800);
FORCEADD UNIVERSAL_GND..1
(-3300 1175);
FORCEPROP 3 LASTPIN (-3300 1225) SIG_NAME GND\g
J 0
(-3290 1235);
DISPLAY 0.659574 (-3290 1235);
PAINT MONO (-3290 1235);
DISPLAY INVISIBLE (-3290 1235);
FORCEPROP 1 LAST PATH I84
J 0
(-3225 1175);
DISPLAY 0.872340 (-3225 1175);
PAINT AQUA (-3225 1175);
DISPLAY INVISIBLE (-3225 1175);
FORCEPROP 1 LAST HDL_POWER GND
J 1
(-3275 1100);
DISPLAY 0.872340 (-3275 1100);
PAINT GREEN (-3275 1100);
DISPLAY INVISIBLE (-3275 1100);
FORCEPROP 2 LAST CDS_LIB logical_power
J 0
(-3300 1175);
PAINT MONO (-3300 1175);
DISPLAY INVISIBLE (-3300 1175);
FORCEADD APX80929SAG7..1
R 2
(-3800 1200);
FORCEPROP 1 LAST PART_NUMBER AL080929000
J 2
(-3575 1467);
DISPLAY 0.723404 (-3575 1467);
PAINT GREEN (-3575 1467);
DISPLAY INVISIBLE (-3575 1467);
FORCEPROP 2 LAST VALUE APX809-29SAG-7
J 2
(-3575 1575);
DISPLAY 1.021277 (-3575 1575);
FORCEPROP 2 LAST PART_TYPE SMLF
J 2
(-3575 1625);
DISPLAY 1.021277 (-3575 1625);
FORCEPROP 1 LAST MATERIAL IC
J 2
(-3575 1410);
DISPLAY 0.723404 (-3575 1410);
PAINT GREEN (-3575 1410);
FORCEPROP 1 LAST $LOCATION U216
J 2
(-3575 1519);
DISPLAY 0.723404 (-3575 1519);
PAINT GREEN (-3575 1519);
FORCEPROP 2 LASTPIN (-3425 1300) $PN 1
J 0
(-3415 1310);
DISPLAY 0.808511 (-3415 1310);
FORCEPROP 2 LASTPIN (-3425 1100) $PN 2
J 0
(-3415 1110);
DISPLAY 0.808511 (-3415 1110);
FORCEPROP 2 LASTPIN (-4175 1200) $PN 3
J 2
(-4185 1210);
DISPLAY 0.808511 (-4185 1210);
FORCEPROP 1 LAST PATH I85
J 2
(-4025 1000);
DISPLAY 0.723404 (-4025 1000);
PAINT GREEN (-4025 1000);
DISPLAY INVISIBLE (-4025 1000);
FORCEPROP 1 LAST CDS_LMAN_SYM_OUTLINE -225,200,225,-200
J 2
(-3800 1200);
DISPLAY 0.468085 (-3800 1200);
PAINT GREEN (-3800 1200);
DISPLAY INVISIBLE (-3800 1200);
FORCEPROP 1 LAST NEEDS_NO_SIZE TRUE
J 2
(-4025 1040);
DISPLAY 0.723404 (-4025 1040);
PAINT GREEN (-4025 1040);
DISPLAY INVISIBLE (-4025 1040);
FORCEPROP 2 LAST CDS_LIB pure_quanta
J 2
(-3800 1200);
PAINT MONO (-3800 1200);
DISPLAY INVISIBLE (-3800 1200);
FORCEPROP 2 LAST CDS_LOCATION U216
J 0
(-3575 1675);
DISPLAY 1.021277 (-3575 1675);
DISPLAY INVISIBLE (-3575 1675);
FORCEPROP 2 LAST $SEC 1
J 0
(-3575 1675);
DISPLAY 0.680851 (-3575 1675);
PAINT MONO (-3575 1675);
DISPLAY INVISIBLE (-3575 1675);
FORCEPROP 2 LAST CDS_SEC 1
J 0
(-3575 1675);
DISPLAY 1.021277 (-3575 1675);
DISPLAY INVISIBLE (-3575 1675);
FORCEADD UNIVERSAL_POWER..1
(-4500 1350);
FORCEPROP 3 LASTPIN (-4500 1300) SIG_NAME P3V3_OCP_V3_2\g
J 0
(-4490 1310);
DISPLAY 0.659574 (-4490 1310);
PAINT MONO (-4490 1310);
DISPLAY INVISIBLE (-4490 1310);
FORCEPROP 1 LAST HDL_POWER P3V3_OCP_V3_2
J 1
(-4500 1400);
DISPLAY 0.872340 (-4500 1400);
PAINT GREEN (-4500 1400);
FORCEPROP 1 LAST PATH I86
J 0
(-4450 1375);
DISPLAY 0.872340 (-4450 1375);
PAINT AQUA (-4450 1375);
DISPLAY INVISIBLE (-4450 1375);
FORCEPROP 2 LAST CDS_LIB logical_power
J 0
(-4500 1350);
DISPLAY INVISIBLE (-4500 1350);
FORCEADD Q_CAP..1
R 2
(-4500 1025);
FORCEPROP 1 LAST PART_NUMBER CH4104K1B00
J 2
(-4550 875);
DISPLAY 0.510638 (-4550 875);
DISPLAY INVISIBLE (-4550 875);
FORCEPROP 1 LAST MATERIAL X7R
J 2
(-4550 925);
DISPLAY 0.510638 (-4550 925);
FORCEPROP 1 LAST VOLTAGE 25V
J 2
(-4550 1025);
DISPLAY 0.510638 (-4550 1025);
FORCEPROP 1 LAST VALUE 0.1UF
J 2
(-4550 1075);
DISPLAY 0.510638 (-4550 1075);
FORCEPROP 1 LAST PACK_TYPE 0402
J 2
(-4550 825);
DISPLAY 0.510638 (-4550 825);
FORCEPROP 1 LAST TOLERANCE 10%
J 2
(-4550 975);
DISPLAY 0.510638 (-4550 975);
FORCEPROP 1 LAST $LOCATION C1819
J 2
(-4550 1125);
DISPLAY 0.978723 (-4550 1125);
FORCEPROP 1 LASTPIN (-4500 1125) $PN 1
J 2
(-4510 1105);
DISPLAY 0.787234 (-4510 1105);
FORCEPROP 1 LASTPIN (-4500 925) $PN 2
J 2
(-4510 905);
DISPLAY 0.787234 (-4510 905);
FORCEPROP 1 LAST PATH I87
J 2
(-4550 1175);
DISPLAY 0.978723 (-4550 1175);
PAINT WHITE (-4550 1175);
DISPLAY INVISIBLE (-4550 1175);
FORCEPROP 2 LAST CDS_LIB pure_quanta
J 2
(-4500 1025);
PAINT MONO (-4500 1025);
DISPLAY INVISIBLE (-4500 1025);
FORCEPROP 2 LAST CDS_LOCATION C1819
J 0
(-4550 1225);
DISPLAY 1.021277 (-4550 1225);
DISPLAY INVISIBLE (-4550 1225);
FORCEPROP 2 LAST $SEC 1
J 0
(-4550 1225);
DISPLAY 0.680851 (-4550 1225);
PAINT MONO (-4550 1225);
DISPLAY INVISIBLE (-4550 1225);
FORCEPROP 2 LAST CDS_SEC 1
J 0
(-4550 1225);
DISPLAY 1.021277 (-4550 1225);
DISPLAY INVISIBLE (-4550 1225);
FORCEADD OFFPAGE..1
(-1525 1000);
FORCEPROP 2 LAST $XR2 214 
J 0
(-2017 1000);
DISPLAY 0.638298 (-2017 1000);
PAINT MONO (-2017 1000);
FORCEPROP 2 LAST $XR1 163 
J 0
(-1897 1000);
DISPLAY 0.638298 (-1897 1000);
PAINT MONO (-1897 1000);
FORCEPROP 2 LAST $XR0 162 
J 0
(-1777 1000);
DISPLAY 0.638298 (-1777 1000);
PAINT MONO (-1777 1000);
FORCEPROP 2 LAST PATH I88
J 0
(-1775 1050);
DISPLAY 1.021277 (-1775 1050);
DISPLAY INVISIBLE (-1775 1050);
FORCEPROP 1 LAST OFFPAGE TRUE
J 0
(-1200 875);
DISPLAY 0.872340 (-1200 875);
PAINT GREEN (-1200 875);
DISPLAY INVISIBLE (-1200 875);
FORCEPROP 1 LAST COMMENT_BODY TRUE
J 0
(-1400 900);
DISPLAY 0.872340 (-1400 900);
PAINT GREEN (-1400 900);
DISPLAY INVISIBLE (-1400 900);
FORCEPROP 2 LAST CDS_LIB standard
J 0
(-1525 1000);
PAINT MONO (-1525 1000);
DISPLAY INVISIBLE (-1525 1000);
FORCEADD UNIVERSAL_POWER..1
(100 1775);
FORCEPROP 3 LASTPIN (100 1725) SIG_NAME P3V3_AUX\g
J 0
(110 1735);
DISPLAY 0.659574 (110 1735);
PAINT MONO (110 1735);
DISPLAY INVISIBLE (110 1735);
FORCEPROP 1 LAST HDL_POWER P3V3_AUX
J 1
(100 1825);
DISPLAY 0.872340 (100 1825);
PAINT GREEN (100 1825);
FORCEPROP 1 LAST PATH I89
J 0
(150 1800);
DISPLAY 0.872340 (150 1800);
PAINT AQUA (150 1800);
DISPLAY INVISIBLE (150 1800);
FORCEPROP 2 LAST CDS_LIB logical_power
J 0
(100 1775);
PAINT MONO (100 1775);
DISPLAY INVISIBLE (100 1775);
FORCEADD 74LVC1G08W57..1
(-3175 -1025);
FORCEPROP 1 LAST PART_NUMBER AL1G0008020
J 0
(-3319 -741);
DISPLAY 0.723404 (-3319 -741);
PAINT GREEN (-3319 -741);
DISPLAY INVISIBLE (-3319 -741);
FORCEPROP 2 LAST VALUE 74LVC1G08W5-7
J 0
(-3550 -675);
DISPLAY 1.021277 (-3550 -675);
FORCEPROP 2 LAST PART_TYPE SMLF
J 0
(-3525 -625);
DISPLAY 1.021277 (-3525 -625);
FORCEPROP 1 LAST MATERIAL IC
J 0
(-3319 -868);
DISPLAY 0.723404 (-3319 -868);
PAINT GREEN (-3319 -868);
FORCEPROP 1 LAST LOCATION U50
J 0
(-3325 -800);
DISPLAY 0.723404 (-3325 -800);
PAINT GREEN (-3325 -800);
FORCEPROP 2 LASTPIN (-3475 -925) $PN 1
J 2
(-3485 -915);
DISPLAY 0.680851 (-3485 -915);
PAINT MONO (-3485 -915);
FORCEPROP 2 LASTPIN (-3475 -1025) $PN 2
J 2
(-3485 -1015);
DISPLAY 0.680851 (-3485 -1015);
PAINT MONO (-3485 -1015);
FORCEPROP 2 LASTPIN (-3475 -1125) $PN 3
J 2
(-3485 -1115);
DISPLAY 0.680851 (-3485 -1115);
PAINT MONO (-3485 -1115);
FORCEPROP 2 LASTPIN (-2875 -925) $PN 5
J 0
(-2865 -915);
DISPLAY 0.680851 (-2865 -915);
PAINT MONO (-2865 -915);
FORCEPROP 2 LASTPIN (-2875 -1075) $PN 4
J 0
(-2865 -1065);
DISPLAY 0.680851 (-2865 -1065);
PAINT MONO (-2865 -1065);
FORCEPROP 1 LAST NEEDS_NO_SIZE TRUE
J 0
(-3175 -1025);
DISPLAY 0.723404 (-3175 -1025);
PAINT GREEN (-3175 -1025);
DISPLAY INVISIBLE (-3175 -1025);
FORCEPROP 1 LAST CDS_LMAN_SYM_OUTLINE -150,150,150,-150
J 0
(-3175 -1025);
DISPLAY 0.468085 (-3175 -1025);
PAINT GREEN (-3175 -1025);
DISPLAY INVISIBLE (-3175 -1025);
FORCEPROP 2 LAST CDS_LIB pure_quanta
J 0
(-3175 -1025);
DISPLAY INVISIBLE (-3175 -1025);
FORCEPROP 1 LAST PATH I9
J 0
(-3175 -1025);
DISPLAY 0.723404 (-3175 -1025);
PAINT GREEN (-3175 -1025);
DISPLAY INVISIBLE (-3175 -1025);
FORCEPROP 2 LAST $SEC 1
J 0
(-3300 -450);
DISPLAY 0.680851 (-3300 -450);
PAINT MONO (-3300 -450);
DISPLAY INVISIBLE (-3300 -450);
FORCEPROP 2 LAST CDS_SEC 1
J 0
(-3300 -450);
DISPLAY 1.021277 (-3300 -450);
DISPLAY INVISIBLE (-3300 -450);
FORCEADD Q_CAP..1
(100 1500);
FORCEPROP 1 LAST PART_NUMBER CH4104K1B00
J 0
(150 1350);
DISPLAY 0.510638 (150 1350);
DISPLAY INVISIBLE (150 1350);
FORCEPROP 1 LAST VALUE 0.1UF
J 0
(150 1550);
DISPLAY 0.510638 (150 1550);
FORCEPROP 1 LAST VOLTAGE 25V
J 0
(150 1500);
DISPLAY 0.510638 (150 1500);
FORCEPROP 1 LAST PACK_TYPE 0402
J 0
(150 1300);
DISPLAY 0.510638 (150 1300);
FORCEPROP 1 LAST TOLERANCE 10%
J 0
(150 1450);
DISPLAY 0.510638 (150 1450);
FORCEPROP 1 LAST MATERIAL X7R
J 0
(150 1400);
DISPLAY 0.510638 (150 1400);
FORCEPROP 1 LAST $LOCATION C2347
J 0
(150 1600);
DISPLAY 0.978723 (150 1600);
FORCEPROP 1 LASTPIN (100 1600) $PN 1
J 0
(110 1580);
DISPLAY 0.787234 (110 1580);
FORCEPROP 1 LASTPIN (100 1400) $PN 2
J 0
(110 1380);
DISPLAY 0.787234 (110 1380);
FORCEPROP 1 LAST PATH I90
J 0
(150 1650);
DISPLAY 0.978723 (150 1650);
PAINT WHITE (150 1650);
DISPLAY INVISIBLE (150 1650);
FORCEPROP 2 LAST CDS_LIB pure_quanta
J 2
(100 1500);
PAINT MONO (100 1500);
DISPLAY INVISIBLE (100 1500);
FORCEPROP 2 LAST CDS_LOCATION C2347
J 0
(150 1700);
DISPLAY 1.021277 (150 1700);
DISPLAY INVISIBLE (150 1700);
FORCEPROP 2 LAST $SEC 1
J 0
(150 1700);
DISPLAY 0.680851 (150 1700);
PAINT MONO (150 1700);
DISPLAY INVISIBLE (150 1700);
FORCEPROP 2 LAST CDS_SEC 1
J 0
(150 1700);
DISPLAY 1.021277 (150 1700);
DISPLAY INVISIBLE (150 1700);
FORCEADD UNIVERSAL_GND..1
(100 1275);
FORCEPROP 3 LASTPIN (100 1325) SIG_NAME GND\g
J 0
(110 1335);
DISPLAY 0.659574 (110 1335);
PAINT MONO (110 1335);
DISPLAY INVISIBLE (110 1335);
FORCEPROP 1 LAST PATH I91
J 0
(175 1275);
DISPLAY 0.872340 (175 1275);
PAINT AQUA (175 1275);
DISPLAY INVISIBLE (175 1275);
FORCEPROP 2 LAST CDS_LIB logical_power
J 0
(100 1275);
PAINT MONO (100 1275);
DISPLAY INVISIBLE (100 1275);
FORCEPROP 1 LAST HDL_POWER GND
J 1
(125 1200);
DISPLAY 0.872340 (125 1200);
PAINT GREEN (125 1200);
DISPLAY INVISIBLE (125 1200);
FORCEADD 74LVC1G08W57..1
(-450 1000);
FORCEPROP 1 LAST PART_NUMBER AL1G0008020
J 0
(-594 1284);
DISPLAY 0.723404 (-594 1284);
PAINT GREEN (-594 1284);
DISPLAY INVISIBLE (-594 1284);
FORCEPROP 1 LAST MATERIAL IC
J 0
(-594 1157);
DISPLAY 0.723404 (-594 1157);
PAINT GREEN (-594 1157);
FORCEPROP 2 LAST PART_TYPE SMLF
J 0
(-825 1475);
DISPLAY 1.021277 (-825 1475);
FORCEPROP 2 LAST VALUE 74LVC1G08W5-7
J 0
(-850 1350);
DISPLAY 1.021277 (-850 1350);
FORCEPROP 1 LAST $LOCATION U323
J 0
(-594 1431);
DISPLAY 0.723404 (-594 1431);
PAINT GREEN (-594 1431);
FORCEPROP 2 LASTPIN (-750 1100) $PN 1
J 2
(-760 1110);
DISPLAY 0.680851 (-760 1110);
PAINT MONO (-760 1110);
FORCEPROP 2 LASTPIN (-750 1000) $PN 2
J 2
(-760 1010);
DISPLAY 0.680851 (-760 1010);
PAINT MONO (-760 1010);
FORCEPROP 2 LASTPIN (-750 900) $PN 3
J 2
(-760 910);
DISPLAY 0.680851 (-760 910);
PAINT MONO (-760 910);
FORCEPROP 2 LASTPIN (-150 1100) $PN 5
J 0
(-140 1110);
DISPLAY 0.680851 (-140 1110);
PAINT MONO (-140 1110);
FORCEPROP 2 LASTPIN (-150 950) $PN 4
J 0
(-140 960);
DISPLAY 0.680851 (-140 960);
PAINT MONO (-140 960);
FORCEPROP 1 LAST PATH I92
J 0
(-450 1000);
DISPLAY 0.723404 (-450 1000);
PAINT GREEN (-450 1000);
DISPLAY INVISIBLE (-450 1000);
FORCEPROP 2 LAST CDS_LIB pure_quanta
J 0
(-450 1000);
DISPLAY INVISIBLE (-450 1000);
FORCEPROP 1 LAST NEEDS_NO_SIZE TRUE
J 0
(-450 1000);
DISPLAY 0.723404 (-450 1000);
PAINT GREEN (-450 1000);
DISPLAY INVISIBLE (-450 1000);
FORCEPROP 1 LAST CDS_LMAN_SYM_OUTLINE -150,150,150,-150
J 0
(-450 1000);
DISPLAY 0.468085 (-450 1000);
PAINT GREEN (-450 1000);
DISPLAY INVISIBLE (-450 1000);
FORCEPROP 0 LAST CDS_LOCATION U323
J 0
(-825 1525);
DISPLAY 1.021277 (-825 1525);
DISPLAY INVISIBLE (-825 1525);
FORCEPROP 2 LAST $SEC 1
J 0
(-825 1525);
DISPLAY 0.680851 (-825 1525);
PAINT MONO (-825 1525);
DISPLAY INVISIBLE (-825 1525);
FORCEPROP 2 LAST CDS_SEC 1
J 0
(-825 1525);
DISPLAY 1.021277 (-825 1525);
DISPLAY INVISIBLE (-825 1525);
FORCEADD UNIVERSAL_GND..1
(-800 775);
FORCEPROP 3 LASTPIN (-800 825) SIG_NAME GND\g
J 0
(-790 835);
DISPLAY 0.659574 (-790 835);
PAINT MONO (-790 835);
DISPLAY INVISIBLE (-790 835);
FORCEPROP 1 LAST PATH I93
J 0
(-725 775);
DISPLAY 0.872340 (-725 775);
PAINT AQUA (-725 775);
DISPLAY INVISIBLE (-725 775);
FORCEPROP 2 LAST CDS_LIB logical_power
J 0
(-800 775);
PAINT MONO (-800 775);
DISPLAY INVISIBLE (-800 775);
FORCEPROP 1 LAST HDL_POWER GND
J 1
(-775 700);
DISPLAY 0.872340 (-775 700);
PAINT GREEN (-775 700);
DISPLAY INVISIBLE (-775 700);
FORCEADD UNIVERSAL_POWER..1
(-1650 1875);
FORCEPROP 3 LASTPIN (-1650 1825) SIG_NAME P3V3_AUX\g
J 0
(-1640 1835);
DISPLAY 0.659574 (-1640 1835);
PAINT MONO (-1640 1835);
DISPLAY INVISIBLE (-1640 1835);
FORCEPROP 1 LAST HDL_POWER P3V3_AUX
J 1
(-1650 1925);
DISPLAY 0.872340 (-1650 1925);
PAINT GREEN (-1650 1925);
FORCEPROP 2 LAST CDS_LIB logical_power
J 0
(-1650 1875);
DISPLAY INVISIBLE (-1650 1875);
FORCEPROP 1 LAST PATH I94
J 0
(-1600 1900);
DISPLAY 0.872340 (-1600 1900);
PAINT AQUA (-1600 1900);
DISPLAY INVISIBLE (-1600 1900);
FORCEADD Q_RES..2
(-1650 1675);
FORCEPROP 1 LAST PART_NUMBER CS21002FB06
J 0
(-1610 1500);
DISPLAY 0.638298 (-1610 1500);
DISPLAY INVISIBLE (-1610 1500);
FORCEPROP 1 LAST VALUE 1K
J 0
(-1605 1750);
DISPLAY 0.638298 (-1605 1750);
FORCEPROP 1 LAST PACK_TYPE 0402LF
J 0
(-1610 1550);
DISPLAY 0.638298 (-1610 1550);
FORCEPROP 1 LAST MATERIAL EMPTY
J 0
(-1610 1600);
DISPLAY 0.638298 (-1610 1600);
PAINT RED (-1610 1600);
FORCEPROP 1 LAST TOLERANCE 1%
J 0
(-1605 1700);
DISPLAY 0.638298 (-1605 1700);
FORCEPROP 1 LAST WATTAGE 1/16W
J 0
(-1610 1650);
DISPLAY 0.638298 (-1610 1650);
FORCEPROP 1 LAST LOCATION R1132
J 0
(-1605 1800);
DISPLAY 0.978723 (-1605 1800);
FORCEPROP 1 LASTPIN (-1650 1775) $PN 1
J 0
(-1645 1737);
DISPLAY 0.787234 (-1645 1737);
FORCEPROP 1 LASTPIN (-1650 1575) $PN 2
J 0
(-1645 1585);
DISPLAY 0.787234 (-1645 1585);
FORCEPROP 1 LAST PATH I95
J 0
(-1600 1850);
DISPLAY 0.978723 (-1600 1850);
PAINT WHITE (-1600 1850);
DISPLAY INVISIBLE (-1600 1850);
FORCEPROP 2 LAST CDS_LIB pure_quanta
J 0
(-1650 1675);
PAINT MONO (-1650 1675);
DISPLAY INVISIBLE (-1650 1675);
FORCEPROP 2 LAST $SEC 1
J 0
(-1600 1900);
DISPLAY 0.680851 (-1600 1900);
PAINT MONO (-1600 1900);
DISPLAY INVISIBLE (-1600 1900);
FORCEPROP 2 LAST CDS_SEC 1
J 0
(-1600 1900);
DISPLAY 1.021277 (-1600 1900);
DISPLAY INVISIBLE (-1600 1900);
FORCEADD Q_RES..1
(-2225 1425);
FORCEPROP 1 LAST PART_NUMBER CS00002JB13
J 0
(-2350 1500);
DISPLAY 0.638298 (-2350 1500);
DISPLAY INVISIBLE (-2350 1500);
FORCEPROP 1 LAST VALUE 0
J 2
(-2050 1425);
DISPLAY 0.638298 (-2050 1425);
FORCEPROP 1 LAST MATERIAL EMPTY
J 0
(-2075 1375);
DISPLAY 0.638298 (-2075 1375);
PAINT RED (-2075 1375);
FORCEPROP 1 LAST TOLERANCE 5%
J 0
(-2025 1425);
DISPLAY 0.638298 (-2025 1425);
FORCEPROP 1 LAST PACK_TYPE 0402LF
J 0
(-1950 1425);
DISPLAY 0.638298 (-1950 1425);
FORCEPROP 1 LAST $LOCATION R4615
J 0
(-2450 1425);
DISPLAY 0.638298 (-2450 1425);
FORCEPROP 1 LASTPIN (-2325 1425) $PN 1
J 0
(-2313 1437);
DISPLAY 0.787234 (-2313 1437);
PAINT MONO (-2313 1437);
FORCEPROP 1 LASTPIN (-2125 1425) $PN 2
J 0
(-2163 1437);
DISPLAY 0.787234 (-2163 1437);
PAINT MONO (-2163 1437);
FORCEPROP 1 LAST PATH I96
J 0
(-2275 1575);
DISPLAY 0.978723 (-2275 1575);
PAINT WHITE (-2275 1575);
DISPLAY INVISIBLE (-2275 1575);
FORCEPROP 2 LAST CDS_LIB pure_quanta
J 0
(-2225 1425);
DISPLAY INVISIBLE (-2225 1425);
FORCEPROP 1 LAST WATTAGE 1/16W
J 2
(-2050 1550);
DISPLAY 0.638298 (-2050 1550);
DISPLAY INVISIBLE (-2050 1550);
FORCEPROP 0 LAST CDS_LOCATION R4615
J 0
(-2275 1525);
DISPLAY 1.021277 (-2275 1525);
DISPLAY INVISIBLE (-2275 1525);
FORCEPROP 0 LAST $SEC 1
J 0
(-2275 1525);
DISPLAY 0.680851 (-2275 1525);
PAINT MONO (-2275 1525);
DISPLAY INVISIBLE (-2275 1525);
FORCEPROP 0 LAST CDS_SEC 1
J 0
(-2275 1525);
DISPLAY 1.021277 (-2275 1525);
DISPLAY INVISIBLE (-2275 1525);
FORCEADD OFFPAGE..1
(-3075 1425);
FORCEPROP 2 LAST $XR0 162 
J 0
(-3327 1425);
DISPLAY 0.638298 (-3327 1425);
PAINT MONO (-3327 1425);
FORCEPROP 2 LAST PATH I98
J 0
(-3325 1475);
DISPLAY 1.021277 (-3325 1475);
DISPLAY INVISIBLE (-3325 1475);
FORCEPROP 1 LAST COMMENT_BODY TRUE
J 0
(-2950 1325);
DISPLAY 0.872340 (-2950 1325);
PAINT GREEN (-2950 1325);
DISPLAY INVISIBLE (-2950 1325);
FORCEPROP 1 LAST OFFPAGE TRUE
J 0
(-2750 1300);
DISPLAY 0.872340 (-2750 1300);
PAINT GREEN (-2750 1300);
DISPLAY INVISIBLE (-2750 1300);
FORCEPROP 2 LAST CDS_LIB standard
J 0
(-3075 1425);
DISPLAY INVISIBLE (-3075 1425);
FORCEADD Q_RES..1
(775 950);
FORCEPROP 1 LAST PART_NUMBER CS03322FB03
J 0
(650 1000);
DISPLAY 0.638298 (650 1000);
DISPLAY INVISIBLE (650 1000);
FORCEPROP 1 LAST VALUE 33.2
J 2
(975 925);
DISPLAY 0.510638 (975 925);
FORCEPROP 1 LAST TOLERANCE 1%
J 0
(1000 925);
DISPLAY 0.510638 (1000 925);
FORCEPROP 1 LAST PACK_TYPE 0402LF
J 0
(1100 925);
DISPLAY 0.510638 (1100 925);
FORCEPROP 1 LAST $LOCATION R4617
J 0
(550 950);
DISPLAY 0.638298 (550 950);
FORCEPROP 1 LASTPIN (675 950) $PN 1
J 0
(687 962);
DISPLAY 0.787234 (687 962);
PAINT MONO (687 962);
FORCEPROP 1 LASTPIN (875 950) $PN 2
J 0
(837 962);
DISPLAY 0.787234 (837 962);
PAINT MONO (837 962);
FORCEPROP 1 LAST MATERIAL CHIP
J 0
(650 1050);
DISPLAY 0.638298 (650 1050);
DISPLAY INVISIBLE (650 1050);
FORCEPROP 1 LAST WATTAGE 1/16W
J 2
(975 1050);
DISPLAY 0.638298 (975 1050);
DISPLAY INVISIBLE (975 1050);
FORCEPROP 1 LAST PATH I99
J 0
(725 1100);
DISPLAY 0.978723 (725 1100);
PAINT WHITE (725 1100);
DISPLAY INVISIBLE (725 1100);
FORCEPROP 2 LAST CDS_LIB pure_quanta
J 0
(775 950);
DISPLAY INVISIBLE (775 950);
FORCEPROP 0 LAST CDS_LOCATION R4617
J 0
(650 1025);
DISPLAY 1.021277 (650 1025);
DISPLAY INVISIBLE (650 1025);
FORCEPROP 0 LAST $SEC 1
J 0
(650 1025);
DISPLAY 0.680851 (650 1025);
PAINT MONO (650 1025);
DISPLAY INVISIBLE (650 1025);
FORCEPROP 0 LAST CDS_SEC 1
J 0
(650 1025);
DISPLAY 1.021277 (650 1025);
DISPLAY INVISIBLE (650 1025);
FORCEADD QUANTA_TITLE_BLOCK_C..1
(3650 -1975);
FORCEPROP 0 LAST CDS_CON_LAST_MODIFIED Fri Aug 25 14:02:34 2023
J 0
(1765 -1960);
DISPLAY INVISIBLE (1765 -1960);
FORCEPROP 1 LAST CUSTOM_TXT_CDS <CON_LAST_MODIFIED>
J 0
(1765 -1960);
DISPLAY 0.978723 (1765 -1960);
FORCEPROP 2 LAST CUSTOM_TXT_CDS <XR_PAGE_TITLE>
J 0
(-4240 3275);
DISPLAY 0.638298 (-4240 3275);
PAINT PINK (-4240 3275);
DISPLAY INVISIBLE (-4240 3275);
FORCEPROP 1 LAST CUSTOM_TXT_CDS <NAME_2>
J 0
(475 -1925);
FORCEPROP 1 LAST CUSTOM_TXT_CDS <NAME_1>
J 0
(475 -1800);
FORCEPROP 1 LAST CUSTOM_TXT_CDS <Q_NUMBER>
J 0
(2247 -1872);
DISPLAY 1.212766 (2247 -1872);
FORCEPROP 1 LAST CUSTOM_TXT_CDS <Q_PROJ>
J 0
(1268 -1873);
DISPLAY 1.212766 (1268 -1873);
FORCEPROP 1 LAST CUSTOM_TXT_CDS <Q_REV>
J 0
(3466 -1872);
DISPLAY 1.212766 (3466 -1872);
FORCEPROP 1 LAST CUSTOM_TXT_CDS <CON_PAGE_NUM> OF <CON_TOTAL_PAGES>
J 0
(3204 -1957);
DISPLAY 0.978723 (3204 -1957);
FORCEPROP 1 LAST Q_TITLE V3_2_OCP3.0 HSC(3/3)
J 0
(-5716 -1949);
DISPLAY 2.446809 (-5716 -1949);
PAINT GREEN (-5716 -1949);
FORCEPROP 1 LAST Q_DEPT 
J 1
(-113 -1926);
DISPLAY 1.957447 (-113 -1926);
PAINT GREEN (-113 -1926);
FORCEPROP 2 LAST CDS_XR_PAGE_TITLE CR-164 : @S9S_MB_2U_LIB.S9S_MB_2U(SCH_1):PAGE164
J 0
(-4240 3275);
DISPLAY 0.638298 (-4240 3275);
PAINT PINK (-4240 3275);
DISPLAY INVISIBLE (-4240 3275);
FORCEPROP 2 LAST PAGE_BORDER TRUE
J 0
(-4240 3275);
DISPLAY 0.638298 (-4240 3275);
PAINT PINK (-4240 3275);
DISPLAY INVISIBLE (-4240 3275);
FORCEPROP 1 LAST COMMENT_BODY TRUE
J 0
(3662 -1988);
DISPLAY 0.978723 (3662 -1988);
PAINT GREEN (3662 -1988);
DISPLAY INVISIBLE (3662 -1988);
FORCEPROP 1 LAST CDS_LMAN_SYM_OUTLINE -9475,6775,100,-125
J 0
(3650 -1975);
DISPLAY 0.468085 (3650 -1975);
PAINT GREEN (3650 -1975);
DISPLAY INVISIBLE (3650 -1975);
FORCEPROP 2 LAST CDS_LIB pure_quanta
J 0
(3650 -1975);
DISPLAY INVISIBLE (3650 -1975);
FORCEADD DNS..2
(-1645 1670);
PAINT RED (-1645 1670);
FORCEPROP 2 LAST CDS_LIB mstr_misc
J 0
(-1645 1670);
PAINT MONO (-1645 1670);
DISPLAY INVISIBLE (-1645 1670);
FORCEPROP 1 LAST COMMENT_BODY TRUE
J 0
(-1645 1670);
DISPLAY INVISIBLE (-1645 1670);
FORCEADD DNS..2
(-2200 1425);
PAINT RED (-2200 1425);
FORCEPROP 2 LAST CDS_LIB mstr_misc
J 0
(-2200 1425);
DISPLAY INVISIBLE (-2200 1425);
FORCEPROP 1 LAST COMMENT_BODY TRUE
R 1
J 0
(-2125 1200);
DISPLAY 0.872340 (-2125 1200);
PAINT GREEN (-2125 1200);
DISPLAY INVISIBLE (-2125 1200);
FORCEADD DNS..2
(-5170 3470);
PAINT RED (-5170 3470);
FORCEPROP 1 LAST COMMENT_BODY TRUE
J 0
(-5170 3470);
DISPLAY INVISIBLE (-5170 3470);
FORCEPROP 2 LAST CDS_LIB mstr_misc
J 0
(-5170 3470);
PAINT MONO (-5170 3470);
DISPLAY INVISIBLE (-5170 3470);
FORCEADD DNS..2
(-4920 3470);
PAINT RED (-4920 3470);
FORCEPROP 1 LAST COMMENT_BODY TRUE
J 0
(-4920 3470);
DISPLAY INVISIBLE (-4920 3470);
FORCEPROP 2 LAST CDS_LIB mstr_misc
J 0
(-4920 3470);
PAINT MONO (-4920 3470);
DISPLAY INVISIBLE (-4920 3470);
FORCEADD DNS..2
(-4670 3470);
PAINT RED (-4670 3470);
FORCEPROP 2 LAST CDS_LIB mstr_misc
J 0
(-4670 3470);
PAINT MONO (-4670 3470);
DISPLAY INVISIBLE (-4670 3470);
FORCEPROP 1 LAST COMMENT_BODY TRUE
J 0
(-4670 3470);
DISPLAY INVISIBLE (-4670 3470);
FORCEADD DNS..2
(1200 -825);
PAINT RED (1200 -825);
FORCEPROP 2 LAST CDS_LIB mstr_misc
J 0
(1200 -825);
DISPLAY INVISIBLE (1200 -825);
FORCEPROP 1 LAST COMMENT_BODY TRUE
R 1
J 0
(1275 -1050);
DISPLAY 0.872340 (1275 -1050);
PAINT GREEN (1275 -1050);
DISPLAY INVISIBLE (1275 -1050);
FORCEADD DNS..2
(1150 250);
PAINT RED (1150 250);
FORCEPROP 2 LAST CDS_LIB mstr_misc
J 0
(1150 250);
DISPLAY INVISIBLE (1150 250);
FORCEPROP 1 LAST COMMENT_BODY TRUE
R 1
J 0
(1225 25);
DISPLAY 0.872340 (1225 25);
PAINT GREEN (1225 25);
DISPLAY INVISIBLE (1225 25);
WIRE 16 -1 (-800 3925)(-800 3850);
WIRE 16 -1 (-4500 1200)(-4500 1300);
WIRE 16 -1 (-4175 1200)(-4500 1200);
WIRE 16 -1 (-4500 1125)(-4500 1200);
WIRE 16 -1 (-1650 1825)(-1650 1775);
WIRE 16 -1 (100 1675)(100 1725);
WIRE 16 -1 (-150 1675)(100 1675);
WIRE 16 -1 (100 1600)(100 1675);
WIRE 16 -1 (-5175 3825)(-5175 3750);
WIRE 16 -1 (-2825 4000)(-2825 3925);
WIRE 16 -1 (2625 1525)(2625 1575);
WIRE 16 -1 (2375 1525)(2625 1525);
WIRE 16 -1 (2625 1450)(2625 1525);
WIRE 16 -1 (-2600 -475)(-2600 -425);
WIRE 16 -1 (-2850 -475)(-2600 -475);
WIRE 16 -1 (-2600 -550)(-2600 -475);
WIRE 16 -1 (-4250 -600)(-4250 -475);
WIRE 16 -1 (-275 100)(-275 150);
WIRE 16 -1 (1550 25)(1550 -25);
WIRE 16 -1 (100 1400)(100 1325);
WIRE 16 -1 (-800 900)(-800 825);
WIRE 16 -1 (-800 900)(-750 900);
WIRE 16 -1 (-3300 1300)(-3300 1225);
WIRE 16 -1 (-3425 1300)(-3300 1300);
WIRE 16 -1 (-4500 925)(-4500 850);
WIRE 16 -1 (-5175 2775)(-5175 2700);
WIRE 16 -1 (-4925 2775)(-4925 2700);
WIRE 16 -1 (-4675 2775)(-4675 2700);
WIRE 16 -1 (-2825 3675)(-2825 3600);
WIRE 16 -1 (2625 1250)(2625 1175);
WIRE 16 -1 (-2250 2550)(-2250 2725);
WIRE 16 -1 (1725 750)(1725 675);
WIRE 16 -1 (1725 750)(1775 750);
WIRE 16 -1 (-2600 -750)(-2600 -825);
WIRE 16 -1 (-3475 -1125)(-3475 -1200);
WIRE 16 -1 (-4250 -1450)(-4250 -1575);
WIRE 16 -1 (600 -550)(600 -625);
WIRE 16 -1 (600 -550)(650 -550);
WIRE 16 -1 (1550 -300)(1550 -375);
WIRE 16 2175 (-975 3550)(-500 3550);
WIRE 16 2175 (-500 4075)(-500 3550);
WIRE 16 2175 (-975 4075)(-975 3550);
WIRE 16 2175 (-975 4075)(-500 4075);
WIRE 16 2175 (-900 1975)(450 1975);
WIRE 16 2175 (450 1975)(450 725);
WIRE 16 2175 (-900 1975)(-900 725);
WIRE 16 2175 (-900 725)(450 725);
WIRE 16 -1 (675 950)(-150 950);
FORCEPROP 0 LAST CDS_PHYS_NET_NAME HP_LVC3_OCP_V3_2_PWRGD
J 0
(340 992);
PAINT MONO (340 992);
DISPLAY INVISIBLE (340 992);
FORCEPROP 2 LAST SIG_NAME HP_LVC3_OCP_V3_2_PWRGD
J 0
(-60 960);
DISPLAY 0.553191 (-60 960);
PAINT WHITE (-60 960);
FORCEPROP 0 LAST $PHYS_NET_NAME RST_PCIE_M2_N
J 0
(340 1039);
PAINT MONO (340 1039);
DISPLAY INVISIBLE (340 1039);
WIRE 16 -1 (-1650 1100)(-2100 1100);
WIRE 16 -1 (-1650 1100)(-750 1100);
FORCEPROP 0 LAST CDS_PHYS_NET_NAME HP_OCP_V3_1_RST_R
J 0
(-1260 1142);
PAINT MONO (-1260 1142);
DISPLAY INVISIBLE (-1260 1142);
FORCEPROP 2 LAST SIG_NAME HP_OCP_V3_2_RST_R
J 0
(-1385 1110);
DISPLAY 0.446809 (-1385 1110);
PAINT WHITE (-1385 1110);
FORCEPROP 0 LAST $PHYS_NET_NAME RST_PCIE_M2_N
J 0
(-1260 1189);
PAINT MONO (-1260 1189);
DISPLAY INVISIBLE (-1260 1189);
WIRE 16 -1 (-1650 1425)(-1650 1100);
WIRE 16 -1 (-1650 1575)(-1650 1425);
WIRE 16 -1 (-2125 1425)(-1650 1425);
WIRE 16 2175 (-3350 1050)(-1725 1050);
WIRE 16 2175 (-1725 1575)(-1725 1050);
WIRE 16 2175 (-3350 1575)(-3350 1050);
WIRE 16 2175 (-3350 1575)(-1725 1575);
WIRE 16 -1 (-1400 2725)(-400 2725);
FORCEPROP 0 LAST CDS_PHYS_NET_NAME TP_PCA9555_0_P17
J 0
(-810 2767);
PAINT MONO (-810 2767);
DISPLAY INVISIBLE (-810 2767);
FORCEPROP 2 LAST SIG_NAME TP_PCA9555_U51_P17
J 0
(-1285 2735);
DISPLAY 0.553191 (-1285 2735);
PAINT WHITE (-1285 2735);
FORCEPROP 0 LAST $PHYS_NET_NAME RST_PCIE_M2_N
J 0
(-810 2814);
PAINT MONO (-810 2814);
DISPLAY INVISIBLE (-810 2814);
WIRE 16 -1 (-1400 2775)(-400 2775);
FORCEPROP 0 LAST CDS_PHYS_NET_NAME TP_PCA9555_0_P16
J 0
(-810 2817);
PAINT MONO (-810 2817);
DISPLAY INVISIBLE (-810 2817);
FORCEPROP 2 LAST SIG_NAME TP_PCA9555_U51_P16
J 0
(-1285 2785);
DISPLAY 0.553191 (-1285 2785);
PAINT WHITE (-1285 2785);
FORCEPROP 0 LAST $PHYS_NET_NAME RST_PCIE_M2_N
J 0
(-810 2864);
PAINT MONO (-810 2864);
DISPLAY INVISIBLE (-810 2864);
WIRE 16 -1 (-1400 2825)(-400 2825);
FORCEPROP 0 LAST CDS_PHYS_NET_NAME TP_PCA9555_0_P15
J 0
(-810 2867);
PAINT MONO (-810 2867);
DISPLAY INVISIBLE (-810 2867);
FORCEPROP 2 LAST SIG_NAME TP_PCA9555_U51_P15
J 0
(-1285 2835);
DISPLAY 0.553191 (-1285 2835);
PAINT WHITE (-1285 2835);
FORCEPROP 0 LAST $PHYS_NET_NAME RST_PCIE_M2_N
J 0
(-810 2914);
PAINT MONO (-810 2914);
DISPLAY INVISIBLE (-810 2914);
WIRE 16 -1 (-1400 2875)(-400 2875);
FORCEPROP 0 LAST CDS_PHYS_NET_NAME TP_PCA9555_0_P14
J 0
(-810 2917);
PAINT MONO (-810 2917);
DISPLAY INVISIBLE (-810 2917);
FORCEPROP 2 LAST SIG_NAME TP_PCA9555_U51_P14
J 0
(-1285 2885);
DISPLAY 0.553191 (-1285 2885);
PAINT WHITE (-1285 2885);
FORCEPROP 0 LAST $PHYS_NET_NAME RST_PCIE_M2_N
J 0
(-810 2964);
PAINT MONO (-810 2964);
DISPLAY INVISIBLE (-810 2964);
WIRE 16 -1 (-1400 2925)(-400 2925);
FORCEPROP 0 LAST CDS_PHYS_NET_NAME TP_PCA9555_0_P13
J 0
(-810 2967);
PAINT MONO (-810 2967);
DISPLAY INVISIBLE (-810 2967);
FORCEPROP 2 LAST SIG_NAME TP_PCA9555_U51_P13
J 0
(-1285 2935);
DISPLAY 0.553191 (-1285 2935);
PAINT WHITE (-1285 2935);
FORCEPROP 0 LAST $PHYS_NET_NAME RST_PCIE_M2_N
J 0
(-810 3014);
PAINT MONO (-810 3014);
DISPLAY INVISIBLE (-810 3014);
WIRE 16 -1 (-1400 2975)(-400 2975);
FORCEPROP 0 LAST CDS_PHYS_NET_NAME TP_PCA9555_0_P12
J 0
(-810 3017);
PAINT MONO (-810 3017);
DISPLAY INVISIBLE (-810 3017);
FORCEPROP 2 LAST SIG_NAME TP_PCA9555_U51_P12
J 0
(-1285 2985);
DISPLAY 0.553191 (-1285 2985);
PAINT WHITE (-1285 2985);
FORCEPROP 0 LAST $PHYS_NET_NAME RST_PCIE_M2_N
J 0
(-810 3064);
PAINT MONO (-810 3064);
DISPLAY INVISIBLE (-810 3064);
WIRE 16 -1 (-1400 3025)(-400 3025);
FORCEPROP 0 LAST CDS_PHYS_NET_NAME TP_PCA9555_0_P11
J 0
(-810 3067);
PAINT MONO (-810 3067);
DISPLAY INVISIBLE (-810 3067);
FORCEPROP 2 LAST SIG_NAME TP_PCA9555_U51_P11
J 0
(-1285 3035);
DISPLAY 0.553191 (-1285 3035);
PAINT WHITE (-1285 3035);
FORCEPROP 0 LAST $PHYS_NET_NAME RST_PCIE_M2_N
J 0
(-810 3114);
PAINT MONO (-810 3114);
DISPLAY INVISIBLE (-810 3114);
WIRE 16 -1 (-800 3650)(-800 3375);
WIRE 16 -1 (-800 3375)(-400 3375);
WIRE 16 -1 (-1400 3375)(-800 3375);
FORCEPROP 0 LAST CDS_PHYS_NET_NAME HP_OCP_V3_1_EN
J 0
(-810 3417);
PAINT MONO (-810 3417);
DISPLAY INVISIBLE (-810 3417);
FORCEPROP 2 LAST SIG_NAME HP_OCP_V3_2_EN
J 0
(-1285 3385);
DISPLAY 0.553191 (-1285 3385);
PAINT WHITE (-1285 3385);
FORCEPROP 0 LAST $PHYS_NET_NAME RST_PCIE_M2_N
J 0
(-810 3464);
PAINT MONO (-810 3464);
DISPLAY INVISIBLE (-810 3464);
WIRE 16 -1 (-1400 3475)(-400 3475);
FORCEPROP 0 LAST CDS_PHYS_NET_NAME TP_PCA9555_0_P00
J 0
(-810 3517);
PAINT MONO (-810 3517);
DISPLAY INVISIBLE (-810 3517);
FORCEPROP 2 LAST SIG_NAME TP_PCA9555_U51_P00
J 0
(-1285 3485);
DISPLAY 0.553191 (-1285 3485);
PAINT WHITE (-1285 3485);
FORCEPROP 0 LAST $PHYS_NET_NAME RST_PCIE_M2_N
J 0
(-810 3564);
PAINT MONO (-810 3564);
DISPLAY INVISIBLE (-810 3564);
WIRE 16 -1 (-1400 3425)(-400 3425);
FORCEPROP 0 LAST CDS_PHYS_NET_NAME TP_PCA9555_0_P01
J 0
(-810 3467);
PAINT MONO (-810 3467);
DISPLAY INVISIBLE (-810 3467);
FORCEPROP 2 LAST SIG_NAME TP_PCA9555_U51_P01
J 0
(-1285 3435);
DISPLAY 0.553191 (-1285 3435);
PAINT WHITE (-1285 3435);
FORCEPROP 0 LAST $PHYS_NET_NAME RST_PCIE_M2_N
J 0
(-810 3514);
PAINT MONO (-810 3514);
DISPLAY INVISIBLE (-810 3514);
WIRE 16 -1 (1550 -100)(1550 -25);
WIRE 16 -1 (1425 -25)(1550 -25);
WIRE 16 -1 (1425 -350)(1425 -25);
WIRE 16 -1 (1250 -350)(1425 -350);
WIRE 16 -1 (-2850 -925)(-2875 -925);
WIRE 16 -1 (-2850 -475)(-2850 -925);
WIRE 16 -1 (-5175 3750)(-5175 3575);
WIRE 16 -1 (-4925 3750)(-5175 3750);
WIRE 16 -1 (-4925 3575)(-4925 3750);
WIRE 16 -1 (-4675 3750)(-4925 3750);
WIRE 16 -1 (-4675 3575)(-4675 3750);
WIRE 16 -1 (-2825 3925)(-2825 3875);
WIRE 16 -1 (-2825 3925)(-2250 3925);
WIRE 16 -1 (-2250 3925)(-2250 3525);
WIRE 16 -1 (-2250 3525)(-2150 3525);
WIRE 16 -1 (-2150 2725)(-2250 2725);
WIRE 16 -1 (2375 950)(2375 1525);
WIRE 16 -1 (-150 1100)(-150 1675);
WIRE 16 -1 (-1400 3325)(-400 3325);
FORCEPROP 0 LAST CDS_PHYS_NET_NAME HP_LVC3_OCP_V3_1_ATTN_OUT_SW_N
J 0
(-810 3367);
PAINT MONO (-810 3367);
DISPLAY INVISIBLE (-810 3367);
FORCEPROP 2 LAST SIG_NAME HP_LVC3_OCP_V3_2_ATTN_OUT_SW_N
J 0
(-1285 3335);
DISPLAY 0.553191 (-1285 3335);
PAINT WHITE (-1285 3335);
FORCEPROP 0 LAST $PHYS_NET_NAME RST_PCIE_M2_N
J 0
(-810 3414);
PAINT MONO (-810 3414);
DISPLAY INVISIBLE (-810 3414);
WIRE 16 -1 (-1400 3275)(-400 3275);
FORCEPROP 0 LAST CDS_PHYS_NET_NAME HP_LVC3_OCP_V3_1_PRSNT2_N
J 0
(-810 3317);
PAINT MONO (-810 3317);
DISPLAY INVISIBLE (-810 3317);
FORCEPROP 2 LAST SIG_NAME HP_LVC3_OCP_V3_2_PRSNT2_N
J 0
(-1285 3285);
DISPLAY 0.553191 (-1285 3285);
PAINT WHITE (-1285 3285);
FORCEPROP 0 LAST $PHYS_NET_NAME RST_PCIE_M2_N
J 0
(-810 3364);
PAINT MONO (-810 3364);
DISPLAY INVISIBLE (-810 3364);
WIRE 16 -1 (-450 -350)(550 -350);
FORCEPROP 0 LAST CDS_PHYS_NET_NAME HP_LVC3_OCP_V3_1_PWRGD_R2
J 0
(-335 -308);
PAINT MONO (-335 -308);
DISPLAY INVISIBLE (-335 -308);
FORCEPROP 2 LAST SIG_NAME HP_LVC3_OCP_V3_2_PWRGD_R2
J 0
(-210 -340);
DISPLAY 0.553191 (-210 -340);
PAINT WHITE (-210 -340);
FORCEPROP 0 LAST $PHYS_NET_NAME RST_PCIE_M2_N
J 0
(-335 -261);
PAINT MONO (-335 -261);
DISPLAY INVISIBLE (-335 -261);
WIRE 16 -1 (550 -350)(650 -350);
WIRE 16 -1 (550 -350)(550 250);
WIRE 16 -1 (550 250)(1025 250);
WIRE 16 -1 (-450 -450)(-275 -450);
FORCEPROP 0 LAST CDS_PHYS_NET_NAME OCP_SFF_AUX_PWR_PLD_EN_R
J 0
(-335 -408);
PAINT MONO (-335 -408);
DISPLAY INVISIBLE (-335 -408);
FORCEPROP 0 LAST $PHYS_NET_NAME RST_PCIE_M2_N
J 0
(-335 -361);
PAINT MONO (-335 -361);
DISPLAY INVISIBLE (-335 -361);
WIRE 16 -1 (-275 -100)(-275 -450);
WIRE 16 -1 (-275 -450)(550 -450);
FORCEPROP 2 LAST SIG_NAME OCP_V3_2_AUX_PWR_PLD_EN_R
J 0
(-210 -440);
DISPLAY 0.553191 (-210 -440);
PAINT WHITE (-210 -440);
WIRE 16 -1 (550 -450)(650 -450);
WIRE 16 -1 (550 -450)(550 -825);
WIRE 16 -1 (550 -825)(1075 -825);
WIRE 16 2175 (-1950 -950)(3600 -950);
WIRE 16 2175 (3600 450)(3600 -950);
WIRE 16 2175 (-1950 450)(-1950 -950);
WIRE 16 2175 (-1950 450)(3600 450);
WIRE 16 -1 (1875 -825)(1275 -825);
WIRE 16 -1 (1250 -500)(1875 -500);
FORCEPROP 0 LAST CDS_PHYS_NET_NAME OCP_SFF_AUX_PWR_EN_R2
J 0
(1365 -458);
PAINT MONO (1365 -458);
DISPLAY INVISIBLE (1365 -458);
FORCEPROP 2 LAST SIG_NAME OCP_V3_2_AUX_PWR_EN_R2
J 0
(1315 -490);
DISPLAY 0.553191 (1315 -490);
PAINT WHITE (1315 -490);
FORCEPROP 0 LAST $PHYS_NET_NAME RST_PCIE_M2_N
J 0
(1365 -411);
PAINT MONO (1365 -411);
DISPLAY INVISIBLE (1365 -411);
WIRE 16 -1 (1875 -500)(1875 -825);
WIRE 16 -1 (1875 -500)(1900 -500);
WIRE 16 -1 (1900 -500)(2075 -500);
WIRE 16 -1 (1900 250)(1900 -500);
WIRE 16 -1 (1225 250)(1900 250);
WIRE 16 -1 (875 950)(950 950);
WIRE 16 -1 (950 950)(1775 950);
FORCEPROP 0 LAST CDS_PHYS_NET_NAME HP_LVC3_OCP_V3_2_PWRGD
J 0
(1265 992);
PAINT MONO (1265 992);
DISPLAY INVISIBLE (1265 992);
FORCEPROP 2 LAST SIG_NAME HP_LVC3_OCP_V3_2_PWRGD_R
J 0
(1065 960);
DISPLAY 0.553191 (1065 960);
PAINT WHITE (1065 960);
FORCEPROP 0 LAST $PHYS_NET_NAME RST_PCIE_M2_N
J 0
(1265 1039);
PAINT MONO (1265 1039);
DISPLAY INVISIBLE (1265 1039);
WIRE 16 -1 (950 950)(950 1225);
WIRE 16 -1 (950 1225)(1125 1225);
WIRE 16 -1 (875 850)(1775 850);
FORCEPROP 0 LAST CDS_PHYS_NET_NAME RST_OCP_V3_1_N
J 0
(1490 892);
PAINT MONO (1490 892);
DISPLAY INVISIBLE (1490 892);
FORCEPROP 2 LAST SIG_NAME RST_OCP_V3_2_N
J 0
(1065 860);
DISPLAY 0.553191 (1065 860);
PAINT WHITE (1065 860);
FORCEPROP 0 LAST $PHYS_NET_NAME RST_PCIE_M2_N
J 0
(1490 939);
PAINT MONO (1490 939);
DISPLAY INVISIBLE (1490 939);
WIRE 16 -1 (-650 -450)(-1475 -450);
FORCEPROP 0 LAST CDS_PHYS_NET_NAME OCP_SFF_AUX_PWR_PLD_EN
J 0
(-1360 -408);
PAINT MONO (-1360 -408);
DISPLAY INVISIBLE (-1360 -408);
FORCEPROP 2 LAST SIG_NAME OCP_V3_2_AUX_PWR_PLD_EN
J 0
(-1485 -440);
DISPLAY 0.553191 (-1485 -440);
PAINT WHITE (-1485 -440);
FORCEPROP 0 LAST $PHYS_NET_NAME RST_PCIE_M2_N
J 0
(-1360 -361);
PAINT MONO (-1360 -361);
DISPLAY INVISIBLE (-1360 -361);
WIRE 16 -1 (-1475 -350)(-650 -350);
FORCEPROP 0 LAST CDS_PHYS_NET_NAME HP_LVC3_OCP_V3_1_PWRGD_R
J 0
(-1360 -308);
PAINT MONO (-1360 -308);
DISPLAY INVISIBLE (-1360 -308);
FORCEPROP 2 LAST SIG_NAME HP_LVC3_OCP_V3_2_PWRGD_R
J 0
(-1485 -340);
DISPLAY 0.553191 (-1485 -340);
PAINT WHITE (-1485 -340);
FORCEPROP 0 LAST $PHYS_NET_NAME RST_PCIE_M2_N
J 0
(-1360 -261);
PAINT MONO (-1360 -261);
DISPLAY INVISIBLE (-1360 -261);
WIRE 16 -1 (2375 800)(3100 800);
FORCEPROP 0 LAST CDS_PHYS_NET_NAME RST_HP_OCP_V3_1_N
J 0
(2715 842);
PAINT MONO (2715 842);
DISPLAY INVISIBLE (2715 842);
FORCEPROP 2 LAST SIG_NAME RST_HP_OCP_V3_2_N
J 0
(2490 810);
DISPLAY 0.553191 (2490 810);
PAINT WHITE (2490 810);
FORCEPROP 0 LAST $PHYS_NET_NAME RST_PCIE_M2_N
J 0
(2715 889);
PAINT MONO (2715 889);
DISPLAY INVISIBLE (2715 889);
WIRE 16 -1 (2275 -500)(3100 -500);
FORCEPROP 0 LAST CDS_PHYS_NET_NAME OCP_SFF_AUX_PWR_EN
J 0
(2390 -458);
PAINT MONO (2390 -458);
DISPLAY INVISIBLE (2390 -458);
FORCEPROP 2 LAST SIG_NAME OCP_V3_2_AUX_PWR_EN
J 0
(2440 -490);
DISPLAY 0.553191 (2440 -490);
PAINT WHITE (2440 -490);
FORCEPROP 0 LAST $PHYS_NET_NAME RST_PCIE_M2_N
J 0
(2390 -411);
PAINT MONO (2390 -411);
DISPLAY INVISIBLE (2390 -411);
WIRE 16 -1 (-5175 -1350)(-4400 -1350);
FORCEPROP 0 LAST CDS_PHYS_NET_NAME HP_LVC3_OCP_V3_1_PRSNT2_N
J 0
(-4685 -1308);
PAINT MONO (-4685 -1308);
DISPLAY INVISIBLE (-4685 -1308);
FORCEPROP 2 LAST SIG_NAME HP_LVC3_OCP_V3_2_PRSNT2_N
J 0
(-5085 -1340);
DISPLAY 0.446809 (-5085 -1340);
PAINT WHITE (-5085 -1340);
FORCEPROP 0 LAST $PHYS_NET_NAME RST_PCIE_M2_N
J 0
(-4685 -1261);
PAINT MONO (-4685 -1261);
DISPLAY INVISIBLE (-4685 -1261);
WIRE 16 -1 (-3900 -925)(-3475 -925);
FORCEPROP 0 LAST CDS_PHYS_NET_NAME HP_OCP_V3_1_EN
J 0
(-3760 -883);
PAINT MONO (-3760 -883);
DISPLAY INVISIBLE (-3760 -883);
FORCEPROP 2 LAST SIG_NAME HP_OCP_V3_2_EN
J 0
(-3860 -915);
DISPLAY 0.446809 (-3860 -915);
PAINT WHITE (-3860 -915);
FORCEPROP 0 LAST $PHYS_NET_NAME RST_PCIE_M2_N
J 0
(-3760 -836);
PAINT MONO (-3760 -836);
DISPLAY INVISIBLE (-3760 -836);
WIRE 16 -1 (-2875 -1075)(-2150 -1075);
FORCEPROP 0 LAST CDS_PHYS_NET_NAME HP_LVC3_OCP_V3_1_EN
J 0
(-2510 -1033);
PAINT MONO (-2510 -1033);
DISPLAY INVISIBLE (-2510 -1033);
FORCEPROP 2 LAST SIG_NAME HP_LVC3_OCP_V3_2_EN
J 0
(-2760 -1065);
DISPLAY 0.553191 (-2760 -1065);
PAINT WHITE (-2760 -1065);
FORCEPROP 0 LAST $PHYS_NET_NAME RST_PCIE_M2_N
J 0
(-2510 -986);
PAINT MONO (-2510 -986);
DISPLAY INVISIBLE (-2510 -986);
WIRE 16 -1 (-4250 -800)(-4250 -1025);
WIRE 16 -1 (-4250 -1025)(-3475 -1025);
FORCEPROP 0 LAST CDS_PHYS_NET_NAME HP_LVC3_OCP_V3_1_PRSNT2
J 0
(-3760 -983);
PAINT MONO (-3760 -983);
DISPLAY INVISIBLE (-3760 -983);
FORCEPROP 2 LAST SIG_NAME HP_LVC3_OCP_V3_2_PRSNT2
J 0
(-4160 -1015);
DISPLAY 0.446809 (-4160 -1015);
PAINT WHITE (-4160 -1015);
FORCEPROP 0 LAST $PHYS_NET_NAME RST_PCIE_M2_N
J 0
(-3760 -936);
PAINT MONO (-3760 -936);
DISPLAY INVISIBLE (-3760 -936);
WIRE 16 -1 (-4250 -1150)(-4250 -1025);
WIRE 16 -1 (-4250 2175)(-3250 2175);
FORCEPROP 0 LAST CDS_PHYS_NET_NAME SMB_PEHPCPU0_LVC3_SCL
J 0
(-3660 2217);
PAINT MONO (-3660 2217);
DISPLAY INVISIBLE (-3660 2217);
FORCEPROP 2 LAST SIG_NAME SMB_PEHPCPU1_LVC3_SCL
J 0
(-4135 2185);
DISPLAY 0.553191 (-4135 2185);
PAINT WHITE (-4135 2185);
FORCEPROP 0 LAST $PHYS_NET_NAME RST_PCIE_M2_N
J 0
(-3660 2264);
PAINT MONO (-3660 2264);
DISPLAY INVISIBLE (-3660 2264);
WIRE 16 -1 (-1400 3075)(-400 3075);
FORCEPROP 0 LAST CDS_PHYS_NET_NAME TP_PCA9555_0_P10
J 0
(-810 3117);
PAINT MONO (-810 3117);
DISPLAY INVISIBLE (-810 3117);
FORCEPROP 2 LAST SIG_NAME TP_PCA9555_U51_P10
J 0
(-1285 3085);
DISPLAY 0.553191 (-1285 3085);
PAINT WHITE (-1285 3085);
FORCEPROP 0 LAST $PHYS_NET_NAME RST_PCIE_M2_N
J 0
(-810 3164);
PAINT MONO (-810 3164);
DISPLAY INVISIBLE (-810 3164);
WIRE 16 -1 (-1400 3125)(-400 3125);
FORCEPROP 0 LAST CDS_PHYS_NET_NAME TP_PCA9555_0_P7
J 0
(-810 3167);
PAINT MONO (-810 3167);
DISPLAY INVISIBLE (-810 3167);
FORCEPROP 2 LAST SIG_NAME TP_PCA9555_U51_P07
J 0
(-1285 3135);
DISPLAY 0.553191 (-1285 3135);
PAINT WHITE (-1285 3135);
FORCEPROP 0 LAST $PHYS_NET_NAME RST_PCIE_M2_N
J 0
(-810 3214);
PAINT MONO (-810 3214);
DISPLAY INVISIBLE (-810 3214);
WIRE 16 -1 (-1400 3175)(-400 3175);
FORCEPROP 0 LAST CDS_PHYS_NET_NAME TP_PCA9555_0_P6
J 0
(-810 3217);
PAINT MONO (-810 3217);
DISPLAY INVISIBLE (-810 3217);
FORCEPROP 2 LAST SIG_NAME TP_PCA9555_U51_P06
J 0
(-1285 3185);
DISPLAY 0.553191 (-1285 3185);
PAINT WHITE (-1285 3185);
FORCEPROP 0 LAST $PHYS_NET_NAME RST_PCIE_M2_N
J 0
(-810 3264);
PAINT MONO (-810 3264);
DISPLAY INVISIBLE (-810 3264);
WIRE 16 -1 (-1400 3225)(-400 3225);
FORCEPROP 0 LAST CDS_PHYS_NET_NAME HP_LVC3_OCP_V3_1_FAULT_N
J 0
(-810 3267);
PAINT MONO (-810 3267);
DISPLAY INVISIBLE (-810 3267);
FORCEPROP 2 LAST SIG_NAME TP_PCA9555_U51_P05
J 0
(-1285 3235);
DISPLAY 0.553191 (-1285 3235);
PAINT WHITE (-1285 3235);
FORCEPROP 0 LAST $PHYS_NET_NAME RST_PCIE_M2_N
J 0
(-810 3314);
PAINT MONO (-810 3314);
DISPLAY INVISIBLE (-810 3314);
WIRE 16 -1 (-2150 3325)(-3150 3325);
FORCEPROP 0 LAST CDS_PHYS_NET_NAME FM_SMB_CPU0_ALERT
J 0
(-2710 3367);
PAINT MONO (-2710 3367);
DISPLAY INVISIBLE (-2710 3367);
FORCEPROP 2 LAST SIG_NAME FM_SMB_CPU1_ALERT
J 0
(-3035 3335);
DISPLAY 0.553191 (-3035 3335);
PAINT WHITE (-3035 3335);
FORCEPROP 0 LAST $PHYS_NET_NAME RST_PCIE_M2_N
J 0
(-2710 3414);
PAINT MONO (-2710 3414);
DISPLAY INVISIBLE (-2710 3414);
WIRE 16 -1 (-5175 2975)(-5175 3125);
WIRE 16 -1 (-5175 3125)(-5175 3375);
WIRE 16 -1 (-5175 3125)(-2150 3125);
FORCEPROP 0 LAST CDS_PHYS_NET_NAME PD_SMB_OCP1_HP_ADD2
J 0
(-2560 3167);
PAINT MONO (-2560 3167);
DISPLAY INVISIBLE (-2560 3167);
FORCEPROP 2 LAST SIG_NAME PD_SMB_OCP2_HP_ADD2
J 0
(-3035 3135);
DISPLAY 0.553191 (-3035 3135);
PAINT WHITE (-3035 3135);
FORCEPROP 0 LAST $PHYS_NET_NAME RST_PCIE_M2_N
J 0
(-2560 3214);
PAINT MONO (-2560 3214);
DISPLAY INVISIBLE (-2560 3214);
WIRE 16 -1 (-3150 2975)(-2150 2975);
FORCEPROP 0 LAST CDS_PHYS_NET_NAME SMB_PEHPCPU1_LVC3_R3_SDA
J 0
(-2710 3017);
PAINT MONO (-2710 3017);
DISPLAY INVISIBLE (-2710 3017);
FORCEPROP 2 LAST SIG_NAME SMB_PEHPCPU1_LVC3_R3_SDA
J 0
(-3035 2985);
DISPLAY 0.553191 (-3035 2985);
PAINT WHITE (-3035 2985);
FORCEPROP 0 LAST $PHYS_NET_NAME RST_PCIE_M2_N
J 0
(-2710 3064);
PAINT MONO (-2710 3064);
DISPLAY INVISIBLE (-2710 3064);
WIRE 16 -1 (-4925 3175)(-4925 2975);
WIRE 16 -1 (-4925 3375)(-4925 3175);
WIRE 16 -1 (-2150 3175)(-4925 3175);
FORCEPROP 0 LAST CDS_PHYS_NET_NAME PD_SMB_OCP1_HP_ADD1
J 0
(-2560 3217);
PAINT MONO (-2560 3217);
DISPLAY INVISIBLE (-2560 3217);
FORCEPROP 2 LAST SIG_NAME PD_SMB_OCP2_HP_ADD1
J 0
(-3035 3185);
DISPLAY 0.553191 (-3035 3185);
PAINT WHITE (-3035 3185);
FORCEPROP 0 LAST $PHYS_NET_NAME RST_PCIE_M2_N
J 0
(-2560 3264);
PAINT MONO (-2560 3264);
DISPLAY INVISIBLE (-2560 3264);
WIRE 16 -1 (-4675 3225)(-4675 2975);
WIRE 16 -1 (-4675 3375)(-4675 3225);
WIRE 16 -1 (-4675 3225)(-2150 3225);
FORCEPROP 0 LAST CDS_PHYS_NET_NAME PD_SMB_OCP1_HP_ADD0
J 0
(-2560 3267);
PAINT MONO (-2560 3267);
DISPLAY INVISIBLE (-2560 3267);
FORCEPROP 2 LAST SIG_NAME PD_SMB_OCP2_HP_ADD0
J 0
(-3035 3235);
DISPLAY 0.553191 (-3035 3235);
PAINT WHITE (-3035 3235);
FORCEPROP 0 LAST $PHYS_NET_NAME RST_PCIE_M2_N
J 0
(-2560 3314);
PAINT MONO (-2560 3314);
DISPLAY INVISIBLE (-2560 3314);
WIRE 16 2175 (-4800 1275)(-4200 1275);
WIRE 16 2175 (-4200 1500)(-4200 1275);
WIRE 16 2175 (-4800 1500)(-4800 1275);
WIRE 16 2175 (-4800 1500)(-4200 1500);
WIRE 16 -1 (-4250 2125)(-3250 2125);
FORCEPROP 0 LAST CDS_PHYS_NET_NAME SMB_PEHPCPU0_LVC3_SDA
J 0
(-3660 2167);
PAINT MONO (-3660 2167);
DISPLAY INVISIBLE (-3660 2167);
FORCEPROP 2 LAST SIG_NAME SMB_PEHPCPU1_LVC3_SDA
J 0
(-4135 2135);
DISPLAY 0.553191 (-4135 2135);
PAINT WHITE (-4135 2135);
FORCEPROP 0 LAST $PHYS_NET_NAME RST_PCIE_M2_N
J 0
(-3660 2214);
PAINT MONO (-3660 2214);
DISPLAY INVISIBLE (-3660 2214);
WIRE 16 -1 (-1600 2125)(-3050 2125);
FORCEPROP 0 LAST CDS_PHYS_NET_NAME SMB_PEHPCPU0_LVC3_R_SDA
J 0
(-2010 2167);
PAINT MONO (-2010 2167);
DISPLAY INVISIBLE (-2010 2167);
FORCEPROP 2 LAST SIG_NAME SMB_PEHPCPU1_LVC3_R3_SDA
J 0
(-2485 2135);
DISPLAY 0.553191 (-2485 2135);
PAINT WHITE (-2485 2135);
FORCEPROP 0 LAST $PHYS_NET_NAME RST_PCIE_M2_N
J 0
(-2010 2214);
PAINT MONO (-2010 2214);
DISPLAY INVISIBLE (-2010 2214);
WIRE 16 -1 (-1600 2175)(-3050 2175);
FORCEPROP 0 LAST CDS_PHYS_NET_NAME SMB_PEHPCPU0_LVC3_R_SCL
J 0
(-2010 2217);
PAINT MONO (-2010 2217);
DISPLAY INVISIBLE (-2010 2217);
FORCEPROP 2 LAST SIG_NAME SMB_PEHPCPU1_LVC3_R3_SCL
J 0
(-2485 2185);
DISPLAY 0.553191 (-2485 2185);
PAINT WHITE (-2485 2185);
FORCEPROP 0 LAST $PHYS_NET_NAME RST_PCIE_M2_N
J 0
(-2010 2264);
PAINT MONO (-2010 2264);
DISPLAY INVISIBLE (-2010 2264);
WIRE 16 -1 (-1600 2075)(-3050 2075);
FORCEPROP 0 LAST CDS_PHYS_NET_NAME FM_SMB_PEHPCPU0_PCIE_ALERT_N
J 0
(-2900 2117);
PAINT MONO (-2900 2117);
DISPLAY INVISIBLE (-2900 2117);
FORCEPROP 0 LAST SIG_NAME FM_SMB_PEHPCPU1_PCIE_ALERT_N
J 0
(-2485 2085);
DISPLAY 0.553191 (-2485 2085);
PAINT WHITE (-2485 2085);
WIRE 16 -1 (-2150 2875)(-3150 2875);
FORCEPROP 0 LAST CDS_PHYS_NET_NAME SMB_PEHPCPU1_LVC3_R3_SCL
J 0
(-2710 2917);
PAINT MONO (-2710 2917);
DISPLAY INVISIBLE (-2710 2917);
FORCEPROP 2 LAST SIG_NAME SMB_PEHPCPU1_LVC3_R3_SCL
J 0
(-3035 2885);
DISPLAY 0.553191 (-3035 2885);
PAINT WHITE (-3035 2885);
FORCEPROP 0 LAST $PHYS_NET_NAME RST_PCIE_M2_N
J 0
(-2710 2964);
PAINT MONO (-2710 2964);
DISPLAY INVISIBLE (-2710 2964);
WIRE 16 -1 (-4250 2075)(-3250 2075);
FORCEPROP 0 LAST CDS_PHYS_NET_NAME FM_SMB_CPU0_ALERT
J 0
(-3810 2117);
PAINT MONO (-3810 2117);
DISPLAY INVISIBLE (-3810 2117);
FORCEPROP 2 LAST SIG_NAME FM_SMB_CPU1_ALERT
J 0
(-4135 2085);
DISPLAY 0.553191 (-4135 2085);
PAINT WHITE (-4135 2085);
WIRE 16 -1 (-3025 1425)(-2325 1425);
FORCEPROP 2 LAST SIG_NAME OCP_V3_2_P3V3_PWRGD
J 0
(-2985 1435);
DISPLAY 0.574468 (-2985 1435);
PAINT WHITE (-2985 1435);
WIRE 16 -1 (-2300 1100)(-3425 1100);
FORCEPROP 0 LAST CDS_PHYS_NET_NAME HP_OCP_V3_1_RST
J 0
(-2585 1142);
PAINT MONO (-2585 1142);
DISPLAY INVISIBLE (-2585 1142);
FORCEPROP 2 LAST SIG_NAME HP_OCP_V3_2_RST
J 0
(-3085 1110);
DISPLAY 0.446809 (-3085 1110);
PAINT WHITE (-3085 1110);
FORCEPROP 0 LAST $PHYS_NET_NAME RST_PCIE_M2_N
J 0
(-2585 1189);
PAINT MONO (-2585 1189);
DISPLAY INVISIBLE (-2585 1189);
WIRE 16 -1 (-1475 1000)(-750 1000);
FORCEPROP 0 LAST CDS_PHYS_NET_NAME HP_LVC3_OCP_V3_1_P12V_PWRGD
J 0
(-1035 1042);
PAINT MONO (-1035 1042);
DISPLAY INVISIBLE (-1035 1042);
FORCEPROP 2 LAST SIG_NAME HP_LVC3_OCP_V3_2_P12V_PWRGD
J 0
(-1385 1010);
DISPLAY 0.446809 (-1385 1010);
PAINT WHITE (-1385 1010);
FORCEPROP 0 LAST $PHYS_NET_NAME RST_PCIE_M2_N
J 0
(-1035 1089);
PAINT MONO (-1035 1089);
DISPLAY INVISIBLE (-1035 1089);
DOT 1 (1875 -500);
DOT 1 (1900 -500);
DOT 1 (2625 1525);
DOT 1 (-2825 3925);
DOT 1 (-4925 3750);
DOT 1 (-4675 3225);
DOT 1 (-4925 3175);
DOT 1 (-5175 3750);
DOT 1 (-5175 3125);
DOT 1 (100 1675);
DOT 1 (-4500 1200);
DOT 1 (-1650 1100);
DOT 1 (-2600 -475);
DOT 1 (-4250 -1025);
DOT 1 (-275 -450);
DOT 1 (550 -450);
DOT 1 (1550 -25);
DOT 1 (950 950);
DOT 1 (550 -350);
DOT 1 (-800 3375);
DOT 1 (-1650 1425);
FORCENOTE
20220803 DESIGN CHANGE
(150 -1025) 0;
DISPLAY LEFT (150 -1025);
DISPLAY 1.276596 (150 -1025);
PAINT PINK (150 -1025);
FORCENOTE
20220224 ADD R4616,R4615
(-3000 875) 0;
DISPLAY LEFT (-3000 875);
DISPLAY 1.021277 (-3000 875);
PAINT PINK (-3000 875);
FORCENOTE
PCA9554 ADDR: 0X40
(-4375 3700) 0;
DISPLAY LEFT (-4375 3700);
DISPLAY 1.595745 (-4375 3700);
PAINT SKYBLUE (-4375 3700);
FORCENOTE
20220224 CHANGE TO P3V3_OCP_V3_2
(-5450 1525) 0;
DISPLAY LEFT (-5450 1525);
DISPLAY 0.808511 (-5450 1525);
PAINT PINK (-5450 1525);
FORCENOTE
PUSH PULL OUTPUT
(-4100 925) 0;
DISPLAY LEFT (-4100 925);
DISPLAY 0.808511 (-4100 925);
PAINT PINK (-4100 925);
FORCENOTE
20220224 ADD U323
(-575 600) 0;
DISPLAY LEFT (-575 600);
DISPLAY 1.021277 (-575 600);
PAINT PINK (-575 600);
FORCENOTE
20220804 ADD R4763
(-1125 4100) 0;
DISPLAY LEFT (-1125 4100);
DISPLAY 1.021277 (-1125 4100);
PAINT PINK (-1125 4100);
FORCENOTE
20210824 MODIFY FOR GT
(-2025 4400) 0;
DISPLAY LEFT (-2025 4400);
DISPLAY 2.510638 (-2025 4400);
PAINT PINK (-2025 4400);
QUIT
